FILE_TYPE = MACRO_DRAWING;
SET COLOR_WIRE YELLOW;
SET COLOR_PROP ORANGE;
SET COLOR_DOT WHITE;
SET COLOR_ARC YELLOW;
SET COLOR_BODY GREEN;
SET COLOR_NOTE PURPLE;
SET PROP_DISPLAY VALUE;
SET PAGE_NUMBER P144;
FORCEADD OFFPAGE..1
(-2200 2625);
FORCEPROP 2 LAST $XR0 173 
J 0
(-2452 2625);
DISPLAY 0.638298 (-2452 2625);
PAINT MONO (-2452 2625);
FORCEPROP 2 LAST PATH I1
J 0
(-2150 2700);
DISPLAY 1.021277 (-2150 2700);
DISPLAY INVISIBLE (-2150 2700);
FORCEPROP 1 LAST OFFPAGE TRUE
J 0
(-1875 2500);
DISPLAY 0.872340 (-1875 2500);
PAINT AQUA (-1875 2500);
DISPLAY INVISIBLE (-1875 2500);
FORCEPROP 1 LAST COMMENT_BODY TRUE
J 0
(-2075 2525);
DISPLAY 0.872340 (-2075 2525);
PAINT GREEN (-2075 2525);
DISPLAY INVISIBLE (-2075 2525);
FORCEPROP 2 LAST CDS_LIB standard
J 0
(-2200 2625);
DISPLAY INVISIBLE (-2200 2625);
FORCEADD OFFPAGE..1
(-2200 3525);
FORCEPROP 2 LAST $XR0 173 
J 0
(-2452 3525);
DISPLAY 0.638298 (-2452 3525);
PAINT MONO (-2452 3525);
FORCEPROP 2 LAST PATH I10
J 0
(-2150 3600);
DISPLAY 1.021277 (-2150 3600);
DISPLAY INVISIBLE (-2150 3600);
FORCEPROP 1 LAST OFFPAGE TRUE
J 0
(-1875 3400);
DISPLAY 0.872340 (-1875 3400);
PAINT AQUA (-1875 3400);
DISPLAY INVISIBLE (-1875 3400);
FORCEPROP 1 LAST COMMENT_BODY TRUE
J 0
(-2075 3425);
DISPLAY 0.872340 (-2075 3425);
PAINT GREEN (-2075 3425);
DISPLAY INVISIBLE (-2075 3425);
FORCEPROP 2 LAST CDS_LIB standard
J 0
(-2200 3525);
DISPLAY INVISIBLE (-2200 3525);
FORCEADD OFFPAGE..1
(-2200 3675);
FORCEPROP 2 LAST $XR0 174 
J 0
(-2452 3675);
DISPLAY 0.638298 (-2452 3675);
PAINT MONO (-2452 3675);
FORCEPROP 2 LAST PATH I11
J 0
(-2150 3750);
DISPLAY 1.021277 (-2150 3750);
DISPLAY INVISIBLE (-2150 3750);
FORCEPROP 2 LAST CDS_LIB standard
J 0
(-2200 3675);
DISPLAY INVISIBLE (-2200 3675);
FORCEPROP 1 LAST COMMENT_BODY TRUE
J 0
(-2075 3575);
DISPLAY 0.872340 (-2075 3575);
PAINT GREEN (-2075 3575);
DISPLAY INVISIBLE (-2075 3575);
FORCEPROP 1 LAST OFFPAGE TRUE
J 0
(-1875 3550);
DISPLAY 0.872340 (-1875 3550);
PAINT AQUA (-1875 3550);
DISPLAY INVISIBLE (-1875 3550);
FORCEADD OFFPAGE..1
(-2200 3625);
FORCEPROP 2 LAST $XR0 174 
J 0
(-2452 3625);
DISPLAY 0.638298 (-2452 3625);
PAINT MONO (-2452 3625);
FORCEPROP 2 LAST PATH I12
J 0
(-2150 3700);
DISPLAY 1.021277 (-2150 3700);
DISPLAY INVISIBLE (-2150 3700);
FORCEPROP 2 LAST CDS_LIB standard
J 0
(-2200 3625);
DISPLAY INVISIBLE (-2200 3625);
FORCEPROP 1 LAST COMMENT_BODY TRUE
J 0
(-2075 3525);
DISPLAY 0.872340 (-2075 3525);
PAINT GREEN (-2075 3525);
DISPLAY INVISIBLE (-2075 3525);
FORCEPROP 1 LAST OFFPAGE TRUE
J 0
(-1875 3500);
DISPLAY 0.872340 (-1875 3500);
PAINT AQUA (-1875 3500);
DISPLAY INVISIBLE (-1875 3500);
FORCEADD OFFPAGE..2
R 2
(-2200 3975);
FORCEPROP 2 LAST $XR0 30 
J 0
(-2454 3975);
DISPLAY 0.638298 (-2454 3975);
PAINT MONO (-2454 3975);
FORCEPROP 2 LAST PATH I13
J 0
(-2150 4050);
DISPLAY 1.021277 (-2150 4050);
DISPLAY INVISIBLE (-2150 4050);
FORCEPROP 1 LAST OFFPAGE TRUE
J 2
(-2525 3850);
DISPLAY 0.872340 (-2525 3850);
PAINT AQUA (-2525 3850);
DISPLAY INVISIBLE (-2525 3850);
FORCEPROP 1 LAST COMMENT_BODY TRUE
J 2
(-2155 3880);
DISPLAY 0.872340 (-2155 3880);
PAINT GREEN (-2155 3880);
DISPLAY INVISIBLE (-2155 3880);
FORCEPROP 2 LAST CDS_LIB standard
J 0
(-2200 3975);
DISPLAY INVISIBLE (-2200 3975);
FORCEADD OFFPAGE..5
(-2200 3925);
FORCEPROP 2 LAST $XR0 30 
J 0
(-2454 3925);
DISPLAY 0.638298 (-2454 3925);
PAINT MONO (-2454 3925);
FORCEPROP 2 LAST PATH I14
J 0
(-2150 4000);
DISPLAY 1.021277 (-2150 4000);
DISPLAY INVISIBLE (-2150 4000);
FORCEPROP 1 LAST OFFPAGE TRUE
J 0
(-1875 3800);
DISPLAY 0.872340 (-1875 3800);
PAINT AQUA (-1875 3800);
DISPLAY INVISIBLE (-1875 3800);
FORCEPROP 1 LAST COMMENT_BODY TRUE
J 0
(-2100 3850);
DISPLAY 1.170213 (-2100 3850);
PAINT GREEN (-2100 3850);
DISPLAY INVISIBLE (-2100 3850);
FORCEPROP 2 LAST CDS_LIB standard
J 0
(-2200 3925);
DISPLAY INVISIBLE (-2200 3925);
FORCEADD OFFPAGE..5
(-2200 3775);
FORCEPROP 2 LAST $XR0 30 
J 0
(-2454 3775);
DISPLAY 0.638298 (-2454 3775);
PAINT MONO (-2454 3775);
FORCEPROP 2 LAST PATH I15
J 0
(-2150 3850);
DISPLAY 1.021277 (-2150 3850);
DISPLAY INVISIBLE (-2150 3850);
FORCEPROP 1 LAST OFFPAGE TRUE
J 0
(-1875 3650);
DISPLAY 0.872340 (-1875 3650);
PAINT AQUA (-1875 3650);
DISPLAY INVISIBLE (-1875 3650);
FORCEPROP 1 LAST COMMENT_BODY TRUE
J 0
(-2100 3700);
DISPLAY 1.170213 (-2100 3700);
PAINT GREEN (-2100 3700);
DISPLAY INVISIBLE (-2100 3700);
FORCEPROP 2 LAST CDS_LIB standard
J 0
(-2200 3775);
DISPLAY INVISIBLE (-2200 3775);
FORCEADD OFFPAGE..2
R 2
(-2200 3825);
FORCEPROP 2 LAST $XR0 30 
J 0
(-2454 3825);
DISPLAY 0.638298 (-2454 3825);
PAINT MONO (-2454 3825);
FORCEPROP 2 LAST PATH I16
J 0
(-2150 3900);
DISPLAY 1.021277 (-2150 3900);
DISPLAY INVISIBLE (-2150 3900);
FORCEPROP 1 LAST OFFPAGE TRUE
J 2
(-2525 3700);
DISPLAY 0.872340 (-2525 3700);
PAINT AQUA (-2525 3700);
DISPLAY INVISIBLE (-2525 3700);
FORCEPROP 1 LAST COMMENT_BODY TRUE
J 2
(-2155 3730);
DISPLAY 0.872340 (-2155 3730);
PAINT GREEN (-2155 3730);
DISPLAY INVISIBLE (-2155 3730);
FORCEPROP 2 LAST CDS_LIB standard
J 0
(-2200 3825);
DISPLAY INVISIBLE (-2200 3825);
FORCEADD UNIVERSAL_GND..1
(-1100 2225);
FORCEPROP 3 LASTPIN (-1100 2275) SIG_NAME GND\g
J 0
(-1090 2285);
DISPLAY 0.659574 (-1090 2285);
PAINT MONO (-1090 2285);
DISPLAY INVISIBLE (-1090 2285);
FORCEPROP 1 LAST PATH I17
J 0
(-1025 2225);
DISPLAY 0.872340 (-1025 2225);
PAINT AQUA (-1025 2225);
DISPLAY INVISIBLE (-1025 2225);
FORCEPROP 2 LAST CDS_LIB logical_power
J 0
(-1100 2225);
DISPLAY INVISIBLE (-1100 2225);
FORCEPROP 1 LAST HDL_POWER GND
J 1
(-1075 2150);
DISPLAY 0.872340 (-1075 2150);
PAINT GREEN (-1075 2150);
DISPLAY INVISIBLE (-1075 2150);
FORCEADD OFFPAGE..1
(-2200 4225);
FORCEPROP 2 LAST $XR0 173 
J 0
(-2452 4225);
DISPLAY 0.638298 (-2452 4225);
PAINT MONO (-2452 4225);
FORCEPROP 2 LAST PATH I18
J 0
(-2150 4300);
DISPLAY 1.021277 (-2150 4300);
DISPLAY INVISIBLE (-2150 4300);
FORCEPROP 2 LAST CDS_LIB standard
J 0
(-2200 4225);
DISPLAY INVISIBLE (-2200 4225);
FORCEPROP 1 LAST COMMENT_BODY TRUE
J 0
(-2075 4125);
DISPLAY 0.872340 (-2075 4125);
PAINT GREEN (-2075 4125);
DISPLAY INVISIBLE (-2075 4125);
FORCEPROP 1 LAST OFFPAGE TRUE
J 0
(-1875 4100);
DISPLAY 0.872340 (-1875 4100);
PAINT AQUA (-1875 4100);
DISPLAY INVISIBLE (-1875 4100);
FORCEADD OFFPAGE..1
(-2200 4275);
FORCEPROP 2 LAST $XR0 173 
J 0
(-2452 4275);
DISPLAY 0.638298 (-2452 4275);
PAINT MONO (-2452 4275);
FORCEPROP 2 LAST PATH I19
J 0
(-2150 4350);
DISPLAY 1.021277 (-2150 4350);
DISPLAY INVISIBLE (-2150 4350);
FORCEPROP 1 LAST OFFPAGE TRUE
J 0
(-1875 4150);
DISPLAY 0.872340 (-1875 4150);
PAINT AQUA (-1875 4150);
DISPLAY INVISIBLE (-1875 4150);
FORCEPROP 1 LAST COMMENT_BODY TRUE
J 0
(-2075 4175);
DISPLAY 0.872340 (-2075 4175);
PAINT GREEN (-2075 4175);
DISPLAY INVISIBLE (-2075 4175);
FORCEPROP 2 LAST CDS_LIB standard
J 0
(-2200 4275);
DISPLAY INVISIBLE (-2200 4275);
FORCEADD OFFPAGE..1
(-2200 2675);
FORCEPROP 2 LAST $XR0 173 
J 0
(-2452 2675);
DISPLAY 0.638298 (-2452 2675);
PAINT MONO (-2452 2675);
FORCEPROP 2 LAST PATH I2
J 0
(-2150 2750);
DISPLAY 1.021277 (-2150 2750);
DISPLAY INVISIBLE (-2150 2750);
FORCEPROP 1 LAST OFFPAGE TRUE
J 0
(-1875 2550);
DISPLAY 0.872340 (-1875 2550);
PAINT AQUA (-1875 2550);
DISPLAY INVISIBLE (-1875 2550);
FORCEPROP 1 LAST COMMENT_BODY TRUE
J 0
(-2075 2575);
DISPLAY 0.872340 (-2075 2575);
PAINT GREEN (-2075 2575);
DISPLAY INVISIBLE (-2075 2575);
FORCEPROP 2 LAST CDS_LIB standard
J 0
(-2200 2675);
DISPLAY INVISIBLE (-2200 2675);
FORCEADD OFFPAGE..1
(-2200 4375);
FORCEPROP 2 LAST $XR0 174 
J 0
(-2452 4375);
DISPLAY 0.638298 (-2452 4375);
PAINT MONO (-2452 4375);
FORCEPROP 2 LAST PATH I20
J 0
(-2150 4450);
DISPLAY 1.021277 (-2150 4450);
DISPLAY INVISIBLE (-2150 4450);
FORCEPROP 2 LAST CDS_LIB standard
J 0
(-2200 4375);
DISPLAY INVISIBLE (-2200 4375);
FORCEPROP 1 LAST COMMENT_BODY TRUE
J 0
(-2075 4275);
DISPLAY 0.872340 (-2075 4275);
PAINT GREEN (-2075 4275);
DISPLAY INVISIBLE (-2075 4275);
FORCEPROP 1 LAST OFFPAGE TRUE
J 0
(-1875 4250);
DISPLAY 0.872340 (-1875 4250);
PAINT AQUA (-1875 4250);
DISPLAY INVISIBLE (-1875 4250);
FORCEADD OFFPAGE..1
(-2200 4425);
FORCEPROP 2 LAST $XR0 174 
J 0
(-2452 4425);
DISPLAY 0.638298 (-2452 4425);
PAINT MONO (-2452 4425);
FORCEPROP 2 LAST PATH I21
J 0
(-2150 4500);
DISPLAY 1.021277 (-2150 4500);
DISPLAY INVISIBLE (-2150 4500);
FORCEPROP 1 LAST OFFPAGE TRUE
J 0
(-1875 4300);
DISPLAY 0.872340 (-1875 4300);
PAINT AQUA (-1875 4300);
DISPLAY INVISIBLE (-1875 4300);
FORCEPROP 1 LAST COMMENT_BODY TRUE
J 0
(-2075 4325);
DISPLAY 0.872340 (-2075 4325);
PAINT GREEN (-2075 4325);
DISPLAY INVISIBLE (-2075 4325);
FORCEPROP 2 LAST CDS_LIB standard
J 0
(-2200 4425);
DISPLAY INVISIBLE (-2200 4425);
FORCEADD OFFPAGE..5
(-2200 4525);
FORCEPROP 2 LAST $XR0 30 
J 0
(-2454 4525);
DISPLAY 0.638298 (-2454 4525);
PAINT MONO (-2454 4525);
FORCEPROP 2 LAST PATH I22
J 0
(-2150 4600);
DISPLAY 1.021277 (-2150 4600);
DISPLAY INVISIBLE (-2150 4600);
FORCEPROP 2 LAST CDS_LIB standard
J 0
(-2200 4525);
DISPLAY INVISIBLE (-2200 4525);
FORCEPROP 1 LAST COMMENT_BODY TRUE
J 0
(-2100 4450);
DISPLAY 1.170213 (-2100 4450);
PAINT GREEN (-2100 4450);
DISPLAY INVISIBLE (-2100 4450);
FORCEPROP 1 LAST OFFPAGE TRUE
J 0
(-1875 4400);
DISPLAY 0.872340 (-1875 4400);
PAINT AQUA (-1875 4400);
DISPLAY INVISIBLE (-1875 4400);
FORCEADD OFFPAGE..2
R 2
(-2200 4725);
FORCEPROP 2 LAST $XR0 30 
J 0
(-2454 4725);
DISPLAY 0.638298 (-2454 4725);
PAINT MONO (-2454 4725);
FORCEPROP 2 LAST PATH I23
J 0
(-2150 4800);
DISPLAY 1.021277 (-2150 4800);
DISPLAY INVISIBLE (-2150 4800);
FORCEPROP 2 LAST CDS_LIB standard
J 0
(-2200 4725);
DISPLAY INVISIBLE (-2200 4725);
FORCEPROP 1 LAST COMMENT_BODY TRUE
J 2
(-2155 4630);
DISPLAY 0.872340 (-2155 4630);
PAINT GREEN (-2155 4630);
DISPLAY INVISIBLE (-2155 4630);
FORCEPROP 1 LAST OFFPAGE TRUE
J 2
(-2525 4600);
DISPLAY 0.872340 (-2525 4600);
PAINT AQUA (-2525 4600);
DISPLAY INVISIBLE (-2525 4600);
FORCEADD OFFPAGE..1
(-2200 5075);
FORCEPROP 2 LAST $XR0 173 
J 0
(-2452 5075);
DISPLAY 0.638298 (-2452 5075);
PAINT MONO (-2452 5075);
FORCEPROP 2 LAST PATH I24
J 0
(-2150 5150);
DISPLAY 1.021277 (-2150 5150);
DISPLAY INVISIBLE (-2150 5150);
FORCEPROP 1 LAST OFFPAGE TRUE
J 0
(-1875 4950);
DISPLAY 0.872340 (-1875 4950);
PAINT AQUA (-1875 4950);
DISPLAY INVISIBLE (-1875 4950);
FORCEPROP 1 LAST COMMENT_BODY TRUE
J 0
(-2075 4975);
DISPLAY 0.872340 (-2075 4975);
PAINT GREEN (-2075 4975);
DISPLAY INVISIBLE (-2075 4975);
FORCEPROP 2 LAST CDS_LIB standard
J 0
(-2200 5075);
DISPLAY INVISIBLE (-2200 5075);
FORCEADD OFFPAGE..5
(-2200 4675);
FORCEPROP 2 LAST $XR0 30 
J 0
(-2454 4675);
DISPLAY 0.638298 (-2454 4675);
PAINT MONO (-2454 4675);
FORCEPROP 2 LAST PATH I25
J 0
(-2150 4750);
DISPLAY 1.021277 (-2150 4750);
DISPLAY INVISIBLE (-2150 4750);
FORCEPROP 2 LAST CDS_LIB standard
J 0
(-2200 4675);
DISPLAY INVISIBLE (-2200 4675);
FORCEPROP 1 LAST COMMENT_BODY TRUE
J 0
(-2100 4600);
DISPLAY 1.170213 (-2100 4600);
PAINT GREEN (-2100 4600);
DISPLAY INVISIBLE (-2100 4600);
FORCEPROP 1 LAST OFFPAGE TRUE
J 0
(-1875 4550);
DISPLAY 0.872340 (-1875 4550);
PAINT AQUA (-1875 4550);
DISPLAY INVISIBLE (-1875 4550);
FORCEADD OFFPAGE..2
R 2
(-2200 4575);
FORCEPROP 2 LAST $XR0 30 
J 0
(-2454 4575);
DISPLAY 0.638298 (-2454 4575);
PAINT MONO (-2454 4575);
FORCEPROP 2 LAST PATH I26
J 0
(-2150 4650);
DISPLAY 1.021277 (-2150 4650);
DISPLAY INVISIBLE (-2150 4650);
FORCEPROP 2 LAST CDS_LIB standard
J 0
(-2200 4575);
DISPLAY INVISIBLE (-2200 4575);
FORCEPROP 1 LAST COMMENT_BODY TRUE
J 2
(-2155 4480);
DISPLAY 0.872340 (-2155 4480);
PAINT GREEN (-2155 4480);
DISPLAY INVISIBLE (-2155 4480);
FORCEPROP 1 LAST OFFPAGE TRUE
J 2
(-2525 4450);
DISPLAY 0.872340 (-2525 4450);
PAINT AQUA (-2525 4450);
DISPLAY INVISIBLE (-2525 4450);
FORCEADD OFFPAGE..1
(-2200 5275);
FORCEPROP 2 LAST $XR0 174 
J 0
(-2452 5275);
DISPLAY 0.638298 (-2452 5275);
PAINT MONO (-2452 5275);
FORCEPROP 2 LAST PATH I27
J 0
(-2150 5350);
DISPLAY 1.021277 (-2150 5350);
DISPLAY INVISIBLE (-2150 5350);
FORCEPROP 1 LAST OFFPAGE TRUE
J 0
(-1875 5150);
DISPLAY 0.872340 (-1875 5150);
PAINT AQUA (-1875 5150);
DISPLAY INVISIBLE (-1875 5150);
FORCEPROP 1 LAST COMMENT_BODY TRUE
J 0
(-2075 5175);
DISPLAY 0.872340 (-2075 5175);
PAINT GREEN (-2075 5175);
DISPLAY INVISIBLE (-2075 5175);
FORCEPROP 2 LAST CDS_LIB standard
J 0
(-2200 5275);
DISPLAY INVISIBLE (-2200 5275);
FORCEADD OFFPAGE..1
(-2200 5225);
FORCEPROP 2 LAST $XR0 174 
J 0
(-2452 5225);
DISPLAY 0.638298 (-2452 5225);
PAINT MONO (-2452 5225);
FORCEPROP 2 LAST PATH I28
J 0
(-2150 5300);
DISPLAY 1.021277 (-2150 5300);
DISPLAY INVISIBLE (-2150 5300);
FORCEPROP 2 LAST CDS_LIB standard
J 0
(-2200 5225);
DISPLAY INVISIBLE (-2200 5225);
FORCEPROP 1 LAST COMMENT_BODY TRUE
J 0
(-2075 5125);
DISPLAY 0.872340 (-2075 5125);
PAINT GREEN (-2075 5125);
DISPLAY INVISIBLE (-2075 5125);
FORCEPROP 1 LAST OFFPAGE TRUE
J 0
(-1875 5100);
DISPLAY 0.872340 (-1875 5100);
PAINT AQUA (-1875 5100);
DISPLAY INVISIBLE (-1875 5100);
FORCEADD OFFPAGE..1
(-2200 5125);
FORCEPROP 2 LAST $XR0 173 
J 0
(-2452 5125);
DISPLAY 0.638298 (-2452 5125);
PAINT MONO (-2452 5125);
FORCEPROP 2 LAST PATH I29
J 0
(-2150 5200);
DISPLAY 1.021277 (-2150 5200);
DISPLAY INVISIBLE (-2150 5200);
FORCEPROP 1 LAST OFFPAGE TRUE
J 0
(-1875 5000);
DISPLAY 0.872340 (-1875 5000);
PAINT AQUA (-1875 5000);
DISPLAY INVISIBLE (-1875 5000);
FORCEPROP 1 LAST COMMENT_BODY TRUE
J 0
(-2075 5025);
DISPLAY 0.872340 (-2075 5025);
PAINT GREEN (-2075 5025);
DISPLAY INVISIBLE (-2075 5025);
FORCEPROP 2 LAST CDS_LIB standard
J 0
(-2200 5125);
DISPLAY INVISIBLE (-2200 5125);
FORCEADD OFFPAGE..1
(-2200 2825);
FORCEPROP 2 LAST $XR0 174 
J 0
(-2452 2825);
DISPLAY 0.638298 (-2452 2825);
PAINT MONO (-2452 2825);
FORCEPROP 2 LAST PATH I3
J 0
(-2150 2900);
DISPLAY 1.021277 (-2150 2900);
DISPLAY INVISIBLE (-2150 2900);
FORCEPROP 1 LAST OFFPAGE TRUE
J 0
(-1875 2700);
DISPLAY 0.872340 (-1875 2700);
PAINT AQUA (-1875 2700);
DISPLAY INVISIBLE (-1875 2700);
FORCEPROP 1 LAST COMMENT_BODY TRUE
J 0
(-2075 2725);
DISPLAY 0.872340 (-2075 2725);
PAINT GREEN (-2075 2725);
DISPLAY INVISIBLE (-2075 2725);
FORCEPROP 2 LAST CDS_LIB standard
J 0
(-2200 2825);
DISPLAY INVISIBLE (-2200 2825);
FORCEADD OFFPAGE..5
(-2200 5525);
FORCEPROP 2 LAST $XR0 30 
J 0
(-2454 5525);
DISPLAY 0.638298 (-2454 5525);
PAINT MONO (-2454 5525);
FORCEPROP 2 LAST PATH I30
J 0
(-2150 5600);
DISPLAY 1.021277 (-2150 5600);
DISPLAY INVISIBLE (-2150 5600);
FORCEPROP 2 LAST CDS_LIB standard
J 0
(-2200 5525);
DISPLAY INVISIBLE (-2200 5525);
FORCEPROP 1 LAST COMMENT_BODY TRUE
J 0
(-2100 5450);
DISPLAY 1.170213 (-2100 5450);
PAINT GREEN (-2100 5450);
DISPLAY INVISIBLE (-2100 5450);
FORCEPROP 1 LAST OFFPAGE TRUE
J 0
(-1875 5400);
DISPLAY 0.872340 (-1875 5400);
PAINT AQUA (-1875 5400);
DISPLAY INVISIBLE (-1875 5400);
FORCEADD OFFPAGE..2
R 2
(-2200 5425);
FORCEPROP 2 LAST $XR0 30 
J 0
(-2454 5425);
DISPLAY 0.638298 (-2454 5425);
PAINT MONO (-2454 5425);
FORCEPROP 2 LAST PATH I31
J 0
(-2150 5500);
DISPLAY 1.021277 (-2150 5500);
DISPLAY INVISIBLE (-2150 5500);
FORCEPROP 1 LAST OFFPAGE TRUE
J 2
(-2525 5300);
DISPLAY 0.872340 (-2525 5300);
PAINT AQUA (-2525 5300);
DISPLAY INVISIBLE (-2525 5300);
FORCEPROP 1 LAST COMMENT_BODY TRUE
J 2
(-2155 5330);
DISPLAY 0.872340 (-2155 5330);
PAINT GREEN (-2155 5330);
DISPLAY INVISIBLE (-2155 5330);
FORCEPROP 2 LAST CDS_LIB standard
J 0
(-2200 5425);
DISPLAY INVISIBLE (-2200 5425);
FORCEADD OFFPAGE..5
(-2200 5375);
FORCEPROP 2 LAST $XR0 30 
J 0
(-2454 5375);
DISPLAY 0.638298 (-2454 5375);
PAINT MONO (-2454 5375);
FORCEPROP 2 LAST PATH I32
J 0
(-2150 5450);
DISPLAY 1.021277 (-2150 5450);
DISPLAY INVISIBLE (-2150 5450);
FORCEPROP 2 LAST CDS_LIB standard
J 0
(-2200 5375);
DISPLAY INVISIBLE (-2200 5375);
FORCEPROP 1 LAST COMMENT_BODY TRUE
J 0
(-2100 5300);
DISPLAY 1.170213 (-2100 5300);
PAINT GREEN (-2100 5300);
DISPLAY INVISIBLE (-2100 5300);
FORCEPROP 1 LAST OFFPAGE TRUE
J 0
(-1875 5250);
DISPLAY 0.872340 (-1875 5250);
PAINT AQUA (-1875 5250);
DISPLAY INVISIBLE (-1875 5250);
FORCEADD OFFPAGE..2
R 2
(-2200 5575);
FORCEPROP 2 LAST $XR0 30 
J 0
(-2454 5575);
DISPLAY 0.638298 (-2454 5575);
PAINT MONO (-2454 5575);
FORCEPROP 2 LAST PATH I33
J 0
(-2150 5650);
DISPLAY 1.021277 (-2150 5650);
DISPLAY INVISIBLE (-2150 5650);
FORCEPROP 2 LAST CDS_LIB standard
J 0
(-2200 5575);
DISPLAY INVISIBLE (-2200 5575);
FORCEPROP 1 LAST COMMENT_BODY TRUE
J 2
(-2155 5480);
DISPLAY 0.872340 (-2155 5480);
PAINT GREEN (-2155 5480);
DISPLAY INVISIBLE (-2155 5480);
FORCEPROP 1 LAST OFFPAGE TRUE
J 2
(-2525 5450);
DISPLAY 0.872340 (-2525 5450);
PAINT AQUA (-2525 5450);
DISPLAY INVISIBLE (-2525 5450);
FORCEADD OFFPAGE..1
(2400 2600);
FORCEPROP 2 LAST $XR0 173 
J 0
(2148 2600);
DISPLAY 0.638298 (2148 2600);
PAINT MONO (2148 2600);
FORCEPROP 2 LAST CDS_LIB standard
J 0
(2400 2600);
DISPLAY INVISIBLE (2400 2600);
FORCEPROP 1 LAST COMMENT_BODY TRUE
J 0
(2525 2500);
DISPLAY 0.872340 (2525 2500);
PAINT GREEN (2525 2500);
DISPLAY INVISIBLE (2525 2500);
FORCEPROP 1 LAST OFFPAGE TRUE
J 0
(2725 2475);
DISPLAY 0.872340 (2725 2475);
PAINT AQUA (2725 2475);
DISPLAY INVISIBLE (2725 2475);
FORCEPROP 2 LAST PATH I34
J 0
(2450 2675);
DISPLAY 1.021277 (2450 2675);
DISPLAY INVISIBLE (2450 2675);
FORCEADD OFFPAGE..1
(2400 2550);
FORCEPROP 2 LAST $XR0 173 
J 0
(2148 2550);
DISPLAY 0.638298 (2148 2550);
PAINT MONO (2148 2550);
FORCEPROP 2 LAST CDS_LIB standard
J 0
(2400 2550);
DISPLAY INVISIBLE (2400 2550);
FORCEPROP 1 LAST COMMENT_BODY TRUE
J 0
(2525 2450);
DISPLAY 0.872340 (2525 2450);
PAINT GREEN (2525 2450);
DISPLAY INVISIBLE (2525 2450);
FORCEPROP 1 LAST OFFPAGE TRUE
J 0
(2725 2425);
DISPLAY 0.872340 (2725 2425);
PAINT AQUA (2725 2425);
DISPLAY INVISIBLE (2725 2425);
FORCEPROP 2 LAST PATH I35
J 0
(2450 2625);
DISPLAY 1.021277 (2450 2625);
DISPLAY INVISIBLE (2450 2625);
FORCEADD OFFPAGE..1
(2400 2700);
FORCEPROP 2 LAST $XR0 174 
J 0
(2148 2700);
DISPLAY 0.638298 (2148 2700);
PAINT MONO (2148 2700);
FORCEPROP 1 LAST OFFPAGE TRUE
J 0
(2725 2575);
DISPLAY 0.872340 (2725 2575);
PAINT AQUA (2725 2575);
DISPLAY INVISIBLE (2725 2575);
FORCEPROP 1 LAST COMMENT_BODY TRUE
J 0
(2525 2600);
DISPLAY 0.872340 (2525 2600);
PAINT GREEN (2525 2600);
DISPLAY INVISIBLE (2525 2600);
FORCEPROP 2 LAST CDS_LIB standard
J 0
(2400 2700);
DISPLAY INVISIBLE (2400 2700);
FORCEPROP 2 LAST PATH I36
J 0
(2450 2775);
DISPLAY 1.021277 (2450 2775);
DISPLAY INVISIBLE (2450 2775);
FORCEADD OFFPAGE..1
(2400 2750);
FORCEPROP 2 LAST $XR0 174 
J 0
(2148 2750);
DISPLAY 0.638298 (2148 2750);
PAINT MONO (2148 2750);
FORCEPROP 1 LAST OFFPAGE TRUE
J 0
(2725 2625);
DISPLAY 0.872340 (2725 2625);
PAINT AQUA (2725 2625);
DISPLAY INVISIBLE (2725 2625);
FORCEPROP 1 LAST COMMENT_BODY TRUE
J 0
(2525 2650);
DISPLAY 0.872340 (2525 2650);
PAINT GREEN (2525 2650);
DISPLAY INVISIBLE (2525 2650);
FORCEPROP 2 LAST CDS_LIB standard
J 0
(2400 2750);
DISPLAY INVISIBLE (2400 2750);
FORCEPROP 2 LAST PATH I37
J 0
(2450 2825);
DISPLAY 1.021277 (2450 2825);
DISPLAY INVISIBLE (2450 2825);
FORCEADD OFFPAGE..5
(2400 2850);
FORCEPROP 2 LAST $XR0 30 
J 0
(2176 2850);
DISPLAY 0.638298 (2176 2850);
PAINT MONO (2176 2850);
FORCEPROP 2 LAST CDS_LIB standard
J 0
(2400 2850);
DISPLAY INVISIBLE (2400 2850);
FORCEPROP 1 LAST COMMENT_BODY TRUE
J 0
(2500 2775);
DISPLAY 1.170213 (2500 2775);
PAINT GREEN (2500 2775);
DISPLAY INVISIBLE (2500 2775);
FORCEPROP 1 LAST OFFPAGE TRUE
J 0
(2725 2725);
DISPLAY 0.872340 (2725 2725);
PAINT AQUA (2725 2725);
DISPLAY INVISIBLE (2725 2725);
FORCEPROP 2 LAST PATH I38
J 0
(2450 2925);
DISPLAY 1.021277 (2450 2925);
DISPLAY INVISIBLE (2450 2925);
FORCEADD OFFPAGE..2
R 2
(2400 2900);
FORCEPROP 2 LAST $XR0 30 
J 0
(2176 2900);
DISPLAY 0.638298 (2176 2900);
PAINT MONO (2176 2900);
FORCEPROP 2 LAST CDS_LIB standard
J 0
(2400 2900);
DISPLAY INVISIBLE (2400 2900);
FORCEPROP 1 LAST COMMENT_BODY TRUE
J 2
(2445 2805);
DISPLAY 0.872340 (2445 2805);
PAINT GREEN (2445 2805);
DISPLAY INVISIBLE (2445 2805);
FORCEPROP 1 LAST OFFPAGE TRUE
J 2
(2075 2775);
DISPLAY 0.872340 (2075 2775);
PAINT AQUA (2075 2775);
DISPLAY INVISIBLE (2075 2775);
FORCEPROP 2 LAST PATH I39
J 0
(2450 2975);
DISPLAY 1.021277 (2450 2975);
DISPLAY INVISIBLE (2450 2975);
FORCEADD OFFPAGE..1
(-2200 2775);
FORCEPROP 2 LAST $XR0 174 
J 0
(-2452 2775);
DISPLAY 0.638298 (-2452 2775);
PAINT MONO (-2452 2775);
FORCEPROP 2 LAST PATH I4
J 0
(-2150 2850);
DISPLAY 1.021277 (-2150 2850);
DISPLAY INVISIBLE (-2150 2850);
FORCEPROP 1 LAST OFFPAGE TRUE
J 0
(-1875 2650);
DISPLAY 0.872340 (-1875 2650);
PAINT AQUA (-1875 2650);
DISPLAY INVISIBLE (-1875 2650);
FORCEPROP 1 LAST COMMENT_BODY TRUE
J 0
(-2075 2675);
DISPLAY 0.872340 (-2075 2675);
PAINT GREEN (-2075 2675);
DISPLAY INVISIBLE (-2075 2675);
FORCEPROP 2 LAST CDS_LIB standard
J 0
(-2200 2775);
DISPLAY INVISIBLE (-2200 2775);
FORCEADD OFFPAGE..2
R 2
(2400 3050);
FORCEPROP 2 LAST $XR0 30 
J 0
(2176 3050);
DISPLAY 0.638298 (2176 3050);
PAINT MONO (2176 3050);
FORCEPROP 2 LAST CDS_LIB standard
J 0
(2400 3050);
DISPLAY INVISIBLE (2400 3050);
FORCEPROP 2 LAST PATH I40
J 0
(2450 3125);
DISPLAY 1.021277 (2450 3125);
DISPLAY INVISIBLE (2450 3125);
FORCEPROP 1 LAST OFFPAGE TRUE
J 2
(2075 2925);
DISPLAY 0.872340 (2075 2925);
PAINT AQUA (2075 2925);
DISPLAY INVISIBLE (2075 2925);
FORCEPROP 1 LAST COMMENT_BODY TRUE
J 2
(2445 2955);
DISPLAY 0.872340 (2445 2955);
PAINT GREEN (2445 2955);
DISPLAY INVISIBLE (2445 2955);
FORCEADD OFFPAGE..5
(2400 3000);
FORCEPROP 2 LAST $XR0 30 
J 0
(2176 3000);
DISPLAY 0.638298 (2176 3000);
PAINT MONO (2176 3000);
FORCEPROP 2 LAST CDS_LIB standard
J 0
(2400 3000);
DISPLAY INVISIBLE (2400 3000);
FORCEPROP 1 LAST COMMENT_BODY TRUE
J 0
(2500 2925);
DISPLAY 1.170213 (2500 2925);
PAINT GREEN (2500 2925);
DISPLAY INVISIBLE (2500 2925);
FORCEPROP 1 LAST OFFPAGE TRUE
J 0
(2725 2875);
DISPLAY 0.872340 (2725 2875);
PAINT AQUA (2725 2875);
DISPLAY INVISIBLE (2725 2875);
FORCEPROP 2 LAST PATH I41
J 0
(2450 3075);
DISPLAY 1.021277 (2450 3075);
DISPLAY INVISIBLE (2450 3075);
FORCEADD OFFPAGE..1
(2400 3400);
FORCEPROP 2 LAST $XR0 173 
J 0
(2148 3400);
DISPLAY 0.638298 (2148 3400);
PAINT MONO (2148 3400);
FORCEPROP 2 LAST CDS_LIB standard
J 0
(2400 3400);
DISPLAY INVISIBLE (2400 3400);
FORCEPROP 1 LAST COMMENT_BODY TRUE
J 0
(2525 3300);
DISPLAY 0.872340 (2525 3300);
PAINT GREEN (2525 3300);
DISPLAY INVISIBLE (2525 3300);
FORCEPROP 1 LAST OFFPAGE TRUE
J 0
(2725 3275);
DISPLAY 0.872340 (2725 3275);
PAINT AQUA (2725 3275);
DISPLAY INVISIBLE (2725 3275);
FORCEPROP 2 LAST PATH I42
J 0
(2450 3475);
DISPLAY 1.021277 (2450 3475);
DISPLAY INVISIBLE (2450 3475);
FORCEADD OFFPAGE..1
(2400 3450);
FORCEPROP 2 LAST $XR0 173 
J 0
(2148 3450);
DISPLAY 0.638298 (2148 3450);
PAINT MONO (2148 3450);
FORCEPROP 2 LAST CDS_LIB standard
J 0
(2400 3450);
DISPLAY INVISIBLE (2400 3450);
FORCEPROP 1 LAST COMMENT_BODY TRUE
J 0
(2525 3350);
DISPLAY 0.872340 (2525 3350);
PAINT GREEN (2525 3350);
DISPLAY INVISIBLE (2525 3350);
FORCEPROP 1 LAST OFFPAGE TRUE
J 0
(2725 3325);
DISPLAY 0.872340 (2725 3325);
PAINT AQUA (2725 3325);
DISPLAY INVISIBLE (2725 3325);
FORCEPROP 2 LAST PATH I43
J 0
(2450 3525);
DISPLAY 1.021277 (2450 3525);
DISPLAY INVISIBLE (2450 3525);
FORCEADD OFFPAGE..1
(2400 3600);
FORCEPROP 2 LAST $XR0 174 
J 0
(2148 3600);
DISPLAY 0.638298 (2148 3600);
PAINT MONO (2148 3600);
FORCEPROP 1 LAST OFFPAGE TRUE
J 0
(2725 3475);
DISPLAY 0.872340 (2725 3475);
PAINT AQUA (2725 3475);
DISPLAY INVISIBLE (2725 3475);
FORCEPROP 1 LAST COMMENT_BODY TRUE
J 0
(2525 3500);
DISPLAY 0.872340 (2525 3500);
PAINT GREEN (2525 3500);
DISPLAY INVISIBLE (2525 3500);
FORCEPROP 2 LAST CDS_LIB standard
J 0
(2400 3600);
DISPLAY INVISIBLE (2400 3600);
FORCEPROP 2 LAST PATH I44
J 0
(2450 3675);
DISPLAY 1.021277 (2450 3675);
DISPLAY INVISIBLE (2450 3675);
FORCEADD OFFPAGE..1
(2400 3550);
FORCEPROP 2 LAST $XR0 174 
J 0
(2148 3550);
DISPLAY 0.638298 (2148 3550);
PAINT MONO (2148 3550);
FORCEPROP 1 LAST OFFPAGE TRUE
J 0
(2725 3425);
DISPLAY 0.872340 (2725 3425);
PAINT AQUA (2725 3425);
DISPLAY INVISIBLE (2725 3425);
FORCEPROP 1 LAST COMMENT_BODY TRUE
J 0
(2525 3450);
DISPLAY 0.872340 (2525 3450);
PAINT GREEN (2525 3450);
DISPLAY INVISIBLE (2525 3450);
FORCEPROP 2 LAST CDS_LIB standard
J 0
(2400 3550);
DISPLAY INVISIBLE (2400 3550);
FORCEPROP 2 LAST PATH I45
J 0
(2450 3625);
DISPLAY 1.021277 (2450 3625);
DISPLAY INVISIBLE (2450 3625);
FORCEADD OFFPAGE..5
(2400 3850);
FORCEPROP 2 LAST $XR0 30 
J 0
(2176 3850);
DISPLAY 0.638298 (2176 3850);
PAINT MONO (2176 3850);
FORCEPROP 1 LAST OFFPAGE TRUE
J 0
(2725 3725);
DISPLAY 0.872340 (2725 3725);
PAINT AQUA (2725 3725);
DISPLAY INVISIBLE (2725 3725);
FORCEPROP 1 LAST COMMENT_BODY TRUE
J 0
(2500 3775);
DISPLAY 1.170213 (2500 3775);
PAINT GREEN (2500 3775);
DISPLAY INVISIBLE (2500 3775);
FORCEPROP 2 LAST CDS_LIB standard
J 0
(2400 3850);
DISPLAY INVISIBLE (2400 3850);
FORCEPROP 2 LAST PATH I46
J 0
(2450 3925);
DISPLAY 1.021277 (2450 3925);
DISPLAY INVISIBLE (2450 3925);
FORCEADD OFFPAGE..2
R 2
(2400 3900);
FORCEPROP 2 LAST $XR0 30 
J 0
(2176 3900);
DISPLAY 0.638298 (2176 3900);
PAINT MONO (2176 3900);
FORCEPROP 1 LAST OFFPAGE TRUE
J 2
(2075 3775);
DISPLAY 0.872340 (2075 3775);
PAINT AQUA (2075 3775);
DISPLAY INVISIBLE (2075 3775);
FORCEPROP 1 LAST COMMENT_BODY TRUE
J 2
(2445 3805);
DISPLAY 0.872340 (2445 3805);
PAINT GREEN (2445 3805);
DISPLAY INVISIBLE (2445 3805);
FORCEPROP 2 LAST CDS_LIB standard
J 0
(2400 3900);
DISPLAY INVISIBLE (2400 3900);
FORCEPROP 2 LAST PATH I47
J 0
(2450 3975);
DISPLAY 1.021277 (2450 3975);
DISPLAY INVISIBLE (2450 3975);
FORCEADD UNIVERSAL_GND..1
(3475 2100);
FORCEPROP 3 LASTPIN (3475 2150) SIG_NAME GND\g
J 0
(3485 2160);
DISPLAY 0.659574 (3485 2160);
PAINT MONO (3485 2160);
DISPLAY INVISIBLE (3485 2160);
FORCEPROP 1 LAST HDL_POWER GND
J 1
(3500 2025);
DISPLAY 0.872340 (3500 2025);
PAINT GREEN (3500 2025);
DISPLAY INVISIBLE (3500 2025);
FORCEPROP 2 LAST CDS_LIB logical_power
J 0
(3475 2100);
DISPLAY INVISIBLE (3475 2100);
FORCEPROP 1 LAST PATH I48
J 0
(3550 2100);
DISPLAY 0.872340 (3550 2100);
PAINT AQUA (3550 2100);
DISPLAY INVISIBLE (3550 2100);
FORCEADD OFFPAGE..1
(2400 4200);
FORCEPROP 2 LAST $XR0 173 
J 0
(2148 4200);
DISPLAY 0.638298 (2148 4200);
PAINT MONO (2148 4200);
FORCEPROP 1 LAST OFFPAGE TRUE
J 0
(2725 4075);
DISPLAY 0.872340 (2725 4075);
PAINT AQUA (2725 4075);
DISPLAY INVISIBLE (2725 4075);
FORCEPROP 1 LAST COMMENT_BODY TRUE
J 0
(2525 4100);
DISPLAY 0.872340 (2525 4100);
PAINT GREEN (2525 4100);
DISPLAY INVISIBLE (2525 4100);
FORCEPROP 2 LAST CDS_LIB standard
J 0
(2400 4200);
DISPLAY INVISIBLE (2400 4200);
FORCEPROP 2 LAST PATH I49
J 0
(2450 4275);
DISPLAY 1.021277 (2450 4275);
DISPLAY INVISIBLE (2450 4275);
FORCEADD OFFPAGE..5
(-2200 2925);
FORCEPROP 2 LAST $XR0 30 
J 0
(-2454 2925);
DISPLAY 0.638298 (-2454 2925);
PAINT MONO (-2454 2925);
FORCEPROP 2 LAST PATH I5
J 0
(-2150 3000);
DISPLAY 1.021277 (-2150 3000);
DISPLAY INVISIBLE (-2150 3000);
FORCEPROP 2 LAST CDS_LIB standard
J 0
(-2200 2925);
DISPLAY INVISIBLE (-2200 2925);
FORCEPROP 1 LAST COMMENT_BODY TRUE
J 0
(-2100 2850);
DISPLAY 1.170213 (-2100 2850);
PAINT GREEN (-2100 2850);
DISPLAY INVISIBLE (-2100 2850);
FORCEPROP 1 LAST OFFPAGE TRUE
J 0
(-1875 2800);
DISPLAY 0.872340 (-1875 2800);
PAINT AQUA (-1875 2800);
DISPLAY INVISIBLE (-1875 2800);
FORCEADD OFFPAGE..1
(2400 4150);
FORCEPROP 2 LAST $XR0 173 
J 0
(2148 4150);
DISPLAY 0.638298 (2148 4150);
PAINT MONO (2148 4150);
FORCEPROP 2 LAST CDS_LIB standard
J 0
(2400 4150);
DISPLAY INVISIBLE (2400 4150);
FORCEPROP 1 LAST COMMENT_BODY TRUE
J 0
(2525 4050);
DISPLAY 0.872340 (2525 4050);
PAINT GREEN (2525 4050);
DISPLAY INVISIBLE (2525 4050);
FORCEPROP 1 LAST OFFPAGE TRUE
J 0
(2725 4025);
DISPLAY 0.872340 (2725 4025);
PAINT AQUA (2725 4025);
DISPLAY INVISIBLE (2725 4025);
FORCEPROP 2 LAST PATH I50
J 0
(2450 4225);
DISPLAY 1.021277 (2450 4225);
DISPLAY INVISIBLE (2450 4225);
FORCEADD OFFPAGE..5
(2400 4450);
FORCEPROP 2 LAST $XR0 30 
J 0
(2176 4450);
DISPLAY 0.638298 (2176 4450);
PAINT MONO (2176 4450);
FORCEPROP 1 LAST OFFPAGE TRUE
J 0
(2725 4325);
DISPLAY 0.872340 (2725 4325);
PAINT AQUA (2725 4325);
DISPLAY INVISIBLE (2725 4325);
FORCEPROP 1 LAST COMMENT_BODY TRUE
J 0
(2500 4375);
DISPLAY 1.170213 (2500 4375);
PAINT GREEN (2500 4375);
DISPLAY INVISIBLE (2500 4375);
FORCEPROP 2 LAST CDS_LIB standard
J 0
(2400 4450);
DISPLAY INVISIBLE (2400 4450);
FORCEPROP 2 LAST PATH I51
J 0
(2450 4525);
DISPLAY 1.021277 (2450 4525);
DISPLAY INVISIBLE (2450 4525);
FORCEADD OFFPAGE..1
(2400 4350);
FORCEPROP 2 LAST $XR0 174 
J 0
(2148 4350);
DISPLAY 0.638298 (2148 4350);
PAINT MONO (2148 4350);
FORCEPROP 1 LAST OFFPAGE TRUE
J 0
(2725 4225);
DISPLAY 0.872340 (2725 4225);
PAINT AQUA (2725 4225);
DISPLAY INVISIBLE (2725 4225);
FORCEPROP 1 LAST COMMENT_BODY TRUE
J 0
(2525 4250);
DISPLAY 0.872340 (2525 4250);
PAINT GREEN (2525 4250);
DISPLAY INVISIBLE (2525 4250);
FORCEPROP 2 LAST CDS_LIB standard
J 0
(2400 4350);
DISPLAY INVISIBLE (2400 4350);
FORCEPROP 2 LAST PATH I52
J 0
(2450 4425);
DISPLAY 1.021277 (2450 4425);
DISPLAY INVISIBLE (2450 4425);
FORCEADD OFFPAGE..1
(2400 4300);
FORCEPROP 2 LAST $XR0 174 
J 0
(2148 4300);
DISPLAY 0.638298 (2148 4300);
PAINT MONO (2148 4300);
FORCEPROP 2 LAST CDS_LIB standard
J 0
(2400 4300);
DISPLAY INVISIBLE (2400 4300);
FORCEPROP 1 LAST COMMENT_BODY TRUE
J 0
(2525 4200);
DISPLAY 0.872340 (2525 4200);
PAINT GREEN (2525 4200);
DISPLAY INVISIBLE (2525 4200);
FORCEPROP 1 LAST OFFPAGE TRUE
J 0
(2725 4175);
DISPLAY 0.872340 (2725 4175);
PAINT AQUA (2725 4175);
DISPLAY INVISIBLE (2725 4175);
FORCEPROP 2 LAST PATH I53
J 0
(2450 4375);
DISPLAY 1.021277 (2450 4375);
DISPLAY INVISIBLE (2450 4375);
FORCEADD OFFPAGE..2
R 2
(2400 4500);
FORCEPROP 2 LAST $XR0 30 
J 0
(2176 4500);
DISPLAY 0.638298 (2176 4500);
PAINT MONO (2176 4500);
FORCEPROP 1 LAST OFFPAGE TRUE
J 2
(2075 4375);
DISPLAY 0.872340 (2075 4375);
PAINT AQUA (2075 4375);
DISPLAY INVISIBLE (2075 4375);
FORCEPROP 1 LAST COMMENT_BODY TRUE
J 2
(2445 4405);
DISPLAY 0.872340 (2445 4405);
PAINT GREEN (2445 4405);
DISPLAY INVISIBLE (2445 4405);
FORCEPROP 2 LAST CDS_LIB standard
J 0
(2400 4500);
DISPLAY INVISIBLE (2400 4500);
FORCEPROP 2 LAST PATH I54
J 0
(2450 4575);
DISPLAY 1.021277 (2450 4575);
DISPLAY INVISIBLE (2450 4575);
FORCEADD OFFPAGE..5
(2400 4600);
FORCEPROP 2 LAST $XR0 30 
J 0
(2176 4600);
DISPLAY 0.638298 (2176 4600);
PAINT MONO (2176 4600);
FORCEPROP 1 LAST OFFPAGE TRUE
J 0
(2725 4475);
DISPLAY 0.872340 (2725 4475);
PAINT AQUA (2725 4475);
DISPLAY INVISIBLE (2725 4475);
FORCEPROP 1 LAST COMMENT_BODY TRUE
J 0
(2500 4525);
DISPLAY 1.170213 (2500 4525);
PAINT GREEN (2500 4525);
DISPLAY INVISIBLE (2500 4525);
FORCEPROP 2 LAST CDS_LIB standard
J 0
(2400 4600);
DISPLAY INVISIBLE (2400 4600);
FORCEPROP 2 LAST PATH I55
J 0
(2450 4675);
DISPLAY 1.021277 (2450 4675);
DISPLAY INVISIBLE (2450 4675);
FORCEADD OFFPAGE..2
R 2
(2400 4650);
FORCEPROP 2 LAST $XR0 30 
J 0
(2176 4650);
DISPLAY 0.638298 (2176 4650);
PAINT MONO (2176 4650);
FORCEPROP 1 LAST OFFPAGE TRUE
J 2
(2075 4525);
DISPLAY 0.872340 (2075 4525);
PAINT AQUA (2075 4525);
DISPLAY INVISIBLE (2075 4525);
FORCEPROP 1 LAST COMMENT_BODY TRUE
J 2
(2445 4555);
DISPLAY 0.872340 (2445 4555);
PAINT GREEN (2445 4555);
DISPLAY INVISIBLE (2445 4555);
FORCEPROP 2 LAST CDS_LIB standard
J 0
(2400 4650);
DISPLAY INVISIBLE (2400 4650);
FORCEPROP 2 LAST PATH I56
J 0
(2450 4725);
DISPLAY 1.021277 (2450 4725);
DISPLAY INVISIBLE (2450 4725);
FORCEADD OFFPAGE..1
(2400 5000);
FORCEPROP 2 LAST $XR0 173 
J 0
(2148 5000);
DISPLAY 0.638298 (2148 5000);
PAINT MONO (2148 5000);
FORCEPROP 2 LAST CDS_LIB standard
J 0
(2400 5000);
DISPLAY INVISIBLE (2400 5000);
FORCEPROP 1 LAST COMMENT_BODY TRUE
J 0
(2525 4900);
DISPLAY 0.872340 (2525 4900);
PAINT GREEN (2525 4900);
DISPLAY INVISIBLE (2525 4900);
FORCEPROP 1 LAST OFFPAGE TRUE
J 0
(2725 4875);
DISPLAY 0.872340 (2725 4875);
PAINT AQUA (2725 4875);
DISPLAY INVISIBLE (2725 4875);
FORCEPROP 2 LAST PATH I57
J 0
(2450 5075);
DISPLAY 1.021277 (2450 5075);
DISPLAY INVISIBLE (2450 5075);
FORCEADD OFFPAGE..1
(2400 5200);
FORCEPROP 2 LAST $XR0 174 
J 0
(2148 5200);
DISPLAY 0.638298 (2148 5200);
PAINT MONO (2148 5200);
FORCEPROP 2 LAST CDS_LIB standard
J 0
(2400 5200);
DISPLAY INVISIBLE (2400 5200);
FORCEPROP 1 LAST COMMENT_BODY TRUE
J 0
(2525 5100);
DISPLAY 0.872340 (2525 5100);
PAINT GREEN (2525 5100);
DISPLAY INVISIBLE (2525 5100);
FORCEPROP 1 LAST OFFPAGE TRUE
J 0
(2725 5075);
DISPLAY 0.872340 (2725 5075);
PAINT AQUA (2725 5075);
DISPLAY INVISIBLE (2725 5075);
FORCEPROP 2 LAST PATH I58
J 0
(2450 5275);
DISPLAY 1.021277 (2450 5275);
DISPLAY INVISIBLE (2450 5275);
FORCEADD OFFPAGE..1
(2400 5150);
FORCEPROP 2 LAST $XR0 174 
J 0
(2148 5150);
DISPLAY 0.638298 (2148 5150);
PAINT MONO (2148 5150);
FORCEPROP 1 LAST OFFPAGE TRUE
J 0
(2725 5025);
DISPLAY 0.872340 (2725 5025);
PAINT AQUA (2725 5025);
DISPLAY INVISIBLE (2725 5025);
FORCEPROP 1 LAST COMMENT_BODY TRUE
J 0
(2525 5050);
DISPLAY 0.872340 (2525 5050);
PAINT GREEN (2525 5050);
DISPLAY INVISIBLE (2525 5050);
FORCEPROP 2 LAST CDS_LIB standard
J 0
(2400 5150);
DISPLAY INVISIBLE (2400 5150);
FORCEPROP 2 LAST PATH I59
J 0
(2450 5225);
DISPLAY 1.021277 (2450 5225);
DISPLAY INVISIBLE (2450 5225);
FORCEADD OFFPAGE..2
R 2
(-2200 2975);
FORCEPROP 2 LAST $XR0 30 
J 0
(-2454 2975);
DISPLAY 0.638298 (-2454 2975);
PAINT MONO (-2454 2975);
FORCEPROP 2 LAST PATH I6
J 0
(-2150 3050);
DISPLAY 1.021277 (-2150 3050);
DISPLAY INVISIBLE (-2150 3050);
FORCEPROP 2 LAST CDS_LIB standard
J 0
(-2200 2975);
DISPLAY INVISIBLE (-2200 2975);
FORCEPROP 1 LAST COMMENT_BODY TRUE
J 2
(-2155 2880);
DISPLAY 0.872340 (-2155 2880);
PAINT GREEN (-2155 2880);
DISPLAY INVISIBLE (-2155 2880);
FORCEPROP 1 LAST OFFPAGE TRUE
J 2
(-2525 2850);
DISPLAY 0.872340 (-2525 2850);
PAINT AQUA (-2525 2850);
DISPLAY INVISIBLE (-2525 2850);
FORCEADD OFFPAGE..1
(2400 5050);
FORCEPROP 2 LAST $XR0 173 
J 0
(2148 5050);
DISPLAY 0.638298 (2148 5050);
PAINT MONO (2148 5050);
FORCEPROP 1 LAST OFFPAGE TRUE
J 0
(2725 4925);
DISPLAY 0.872340 (2725 4925);
PAINT AQUA (2725 4925);
DISPLAY INVISIBLE (2725 4925);
FORCEPROP 1 LAST COMMENT_BODY TRUE
J 0
(2525 4950);
DISPLAY 0.872340 (2525 4950);
PAINT GREEN (2525 4950);
DISPLAY INVISIBLE (2525 4950);
FORCEPROP 2 LAST CDS_LIB standard
J 0
(2400 5050);
DISPLAY INVISIBLE (2400 5050);
FORCEPROP 2 LAST PATH I60
J 0
(2450 5125);
DISPLAY 1.021277 (2450 5125);
DISPLAY INVISIBLE (2450 5125);
FORCEADD OFFPAGE..2
R 2
(2400 5350);
FORCEPROP 2 LAST $XR0 30 
J 0
(2176 5350);
DISPLAY 0.638298 (2176 5350);
PAINT MONO (2176 5350);
FORCEPROP 2 LAST CDS_LIB standard
J 0
(2400 5350);
DISPLAY INVISIBLE (2400 5350);
FORCEPROP 1 LAST COMMENT_BODY TRUE
J 2
(2445 5255);
DISPLAY 0.872340 (2445 5255);
PAINT GREEN (2445 5255);
DISPLAY INVISIBLE (2445 5255);
FORCEPROP 1 LAST OFFPAGE TRUE
J 2
(2075 5225);
DISPLAY 0.872340 (2075 5225);
PAINT AQUA (2075 5225);
DISPLAY INVISIBLE (2075 5225);
FORCEPROP 2 LAST PATH I61
J 0
(2450 5425);
DISPLAY 1.021277 (2450 5425);
DISPLAY INVISIBLE (2450 5425);
FORCEADD OFFPAGE..5
(2400 5300);
FORCEPROP 2 LAST $XR0 30 
J 0
(2176 5300);
DISPLAY 0.638298 (2176 5300);
PAINT MONO (2176 5300);
FORCEPROP 2 LAST CDS_LIB standard
J 0
(2400 5300);
DISPLAY INVISIBLE (2400 5300);
FORCEPROP 1 LAST COMMENT_BODY TRUE
J 0
(2500 5225);
DISPLAY 1.170213 (2500 5225);
PAINT GREEN (2500 5225);
DISPLAY INVISIBLE (2500 5225);
FORCEPROP 1 LAST OFFPAGE TRUE
J 0
(2725 5175);
DISPLAY 0.872340 (2725 5175);
PAINT AQUA (2725 5175);
DISPLAY INVISIBLE (2725 5175);
FORCEPROP 2 LAST PATH I62
J 0
(2450 5375);
DISPLAY 1.021277 (2450 5375);
DISPLAY INVISIBLE (2450 5375);
FORCEADD OFFPAGE..2
R 2
(2400 5500);
FORCEPROP 2 LAST $XR0 30 
J 0
(2176 5500);
DISPLAY 0.638298 (2176 5500);
PAINT MONO (2176 5500);
FORCEPROP 1 LAST OFFPAGE TRUE
J 2
(2075 5375);
DISPLAY 0.872340 (2075 5375);
PAINT AQUA (2075 5375);
DISPLAY INVISIBLE (2075 5375);
FORCEPROP 1 LAST COMMENT_BODY TRUE
J 2
(2445 5405);
DISPLAY 0.872340 (2445 5405);
PAINT GREEN (2445 5405);
DISPLAY INVISIBLE (2445 5405);
FORCEPROP 2 LAST CDS_LIB standard
J 0
(2400 5500);
DISPLAY INVISIBLE (2400 5500);
FORCEPROP 2 LAST PATH I63
J 0
(2450 5575);
DISPLAY 1.021277 (2450 5575);
DISPLAY INVISIBLE (2450 5575);
FORCEADD OFFPAGE..5
(2400 5450);
FORCEPROP 2 LAST $XR0 30 
J 0
(2176 5450);
DISPLAY 0.638298 (2176 5450);
PAINT MONO (2176 5450);
FORCEPROP 1 LAST OFFPAGE TRUE
J 0
(2725 5325);
DISPLAY 0.872340 (2725 5325);
PAINT AQUA (2725 5325);
DISPLAY INVISIBLE (2725 5325);
FORCEPROP 1 LAST COMMENT_BODY TRUE
J 0
(2500 5375);
DISPLAY 1.170213 (2500 5375);
PAINT GREEN (2500 5375);
DISPLAY INVISIBLE (2500 5375);
FORCEPROP 2 LAST CDS_LIB standard
J 0
(2400 5450);
DISPLAY INVISIBLE (2400 5450);
FORCEPROP 2 LAST PATH I64
J 0
(2450 5525);
DISPLAY 1.021277 (2450 5525);
DISPLAY INVISIBLE (2450 5525);
FORCEADD CONN112_10137002101LF..2
(4625 4050);
FORCEPROP 1 LAST PART_NUMBER DFHSB2FR012
J 0
(3875 5825);
DISPLAY 0.723404 (3875 5825);
PAINT GREEN (3875 5825);
DISPLAY INVISIBLE (3875 5825);
FORCEPROP 2 LAST PART_TYPE THLF
J 0
(3875 5950);
DISPLAY 1.021277 (3875 5950);
FORCEPROP 1 LAST MATERIAL IO
J 0
(3883 5763);
DISPLAY 0.723404 (3883 5763);
PAINT GREEN (3883 5763);
FORCEPROP 1 LAST LOCATION J106
J 0
(3875 5875);
DISPLAY 0.723404 (3875 5875);
PAINT GREEN (3875 5875);
FORCEPROP 0 LASTPIN (3700 3150) $PN A1
J 2
(3690 3160);
DISPLAY 0.680851 (3690 3160);
PAINT MONO (3690 3160);
FORCEPROP 0 LASTPIN (3700 3950) $PN A2
J 2
(3690 3960);
DISPLAY 0.680851 (3690 3960);
PAINT MONO (3690 3960);
FORCEPROP 0 LASTPIN (3700 4750) $PN A3
J 2
(3690 4760);
DISPLAY 0.680851 (3690 4760);
PAINT MONO (3690 4760);
FORCEPROP 0 LASTPIN (3700 5550) $PN A4
J 2
(3690 5560);
DISPLAY 0.680851 (3690 5560);
PAINT MONO (3690 5560);
FORCEPROP 0 LASTPIN (3700 3100) $PN B1
J 2
(3690 3110);
DISPLAY 0.680851 (3690 3110);
PAINT MONO (3690 3110);
FORCEPROP 0 LASTPIN (3700 3900) $PN B2
J 2
(3690 3910);
DISPLAY 0.680851 (3690 3910);
PAINT MONO (3690 3910);
FORCEPROP 0 LASTPIN (3700 4700) $PN B3
J 2
(3690 4710);
DISPLAY 0.680851 (3690 4710);
PAINT MONO (3690 4710);
FORCEPROP 0 LASTPIN (3700 5500) $PN B4
J 2
(3690 5510);
DISPLAY 0.680851 (3690 5510);
PAINT MONO (3690 5510);
FORCEPROP 0 LASTPIN (3700 3050) $PN C1
J 2
(3690 3060);
DISPLAY 0.680851 (3690 3060);
PAINT MONO (3690 3060);
FORCEPROP 0 LASTPIN (3700 3850) $PN C2
J 2
(3690 3860);
DISPLAY 0.680851 (3690 3860);
PAINT MONO (3690 3860);
FORCEPROP 0 LASTPIN (3700 4650) $PN C3
J 2
(3690 4660);
DISPLAY 0.680851 (3690 4660);
PAINT MONO (3690 4660);
FORCEPROP 0 LASTPIN (3700 5450) $PN C4
J 2
(3690 5460);
DISPLAY 0.680851 (3690 5460);
PAINT MONO (3690 5460);
FORCEPROP 0 LASTPIN (3700 3000) $PN D1
J 2
(3690 3010);
DISPLAY 0.680851 (3690 3010);
PAINT MONO (3690 3010);
FORCEPROP 0 LASTPIN (3700 3800) $PN D2
J 2
(3690 3810);
DISPLAY 0.680851 (3690 3810);
PAINT MONO (3690 3810);
FORCEPROP 0 LASTPIN (3700 4600) $PN D3
J 2
(3690 4610);
DISPLAY 0.680851 (3690 4610);
PAINT MONO (3690 4610);
FORCEPROP 0 LASTPIN (3700 5400) $PN D4
J 2
(3690 5410);
DISPLAY 0.680851 (3690 5410);
PAINT MONO (3690 5410);
FORCEPROP 0 LASTPIN (3700 2950) $PN E1
J 2
(3690 2960);
DISPLAY 0.680851 (3690 2960);
PAINT MONO (3690 2960);
FORCEPROP 0 LASTPIN (3700 3750) $PN E2
J 2
(3690 3760);
DISPLAY 0.680851 (3690 3760);
PAINT MONO (3690 3760);
FORCEPROP 0 LASTPIN (3700 4550) $PN E3
J 2
(3690 4560);
DISPLAY 0.680851 (3690 4560);
PAINT MONO (3690 4560);
FORCEPROP 0 LASTPIN (3700 5350) $PN E4
J 2
(3690 5360);
DISPLAY 0.680851 (3690 5360);
PAINT MONO (3690 5360);
FORCEPROP 0 LASTPIN (3700 2900) $PN F1
J 2
(3690 2910);
DISPLAY 0.680851 (3690 2910);
PAINT MONO (3690 2910);
FORCEPROP 0 LASTPIN (3700 3700) $PN F2
J 2
(3690 3710);
DISPLAY 0.680851 (3690 3710);
PAINT MONO (3690 3710);
FORCEPROP 0 LASTPIN (3700 4500) $PN F3
J 2
(3690 4510);
DISPLAY 0.680851 (3690 4510);
PAINT MONO (3690 4510);
FORCEPROP 0 LASTPIN (3700 5300) $PN F4
J 2
(3690 5310);
DISPLAY 0.680851 (3690 5310);
PAINT MONO (3690 5310);
FORCEPROP 0 LASTPIN (3700 2850) $PN G1
J 2
(3690 2860);
DISPLAY 0.680851 (3690 2860);
PAINT MONO (3690 2860);
FORCEPROP 0 LASTPIN (3700 3650) $PN G2
J 2
(3690 3660);
DISPLAY 0.680851 (3690 3660);
PAINT MONO (3690 3660);
FORCEPROP 0 LASTPIN (3700 4450) $PN G3
J 2
(3690 4460);
DISPLAY 0.680851 (3690 4460);
PAINT MONO (3690 4460);
FORCEPROP 0 LASTPIN (3700 5250) $PN G4
J 2
(3690 5260);
DISPLAY 0.680851 (3690 5260);
PAINT MONO (3690 5260);
FORCEPROP 0 LASTPIN (3700 2800) $PN H1
J 2
(3690 2810);
DISPLAY 0.680851 (3690 2810);
PAINT MONO (3690 2810);
FORCEPROP 0 LASTPIN (3700 3600) $PN H2
J 2
(3690 3610);
DISPLAY 0.680851 (3690 3610);
PAINT MONO (3690 3610);
FORCEPROP 0 LASTPIN (3700 4400) $PN H3
J 2
(3690 4410);
DISPLAY 0.680851 (3690 4410);
PAINT MONO (3690 4410);
FORCEPROP 0 LASTPIN (3700 5200) $PN H4
J 2
(3690 5210);
DISPLAY 0.680851 (3690 5210);
PAINT MONO (3690 5210);
FORCEPROP 0 LASTPIN (3700 2750) $PN I1
J 2
(3690 2760);
DISPLAY 0.680851 (3690 2760);
PAINT MONO (3690 2760);
FORCEPROP 0 LASTPIN (3700 3550) $PN I2
J 2
(3690 3560);
DISPLAY 0.680851 (3690 3560);
PAINT MONO (3690 3560);
FORCEPROP 0 LASTPIN (3700 4350) $PN I3
J 2
(3690 4360);
DISPLAY 0.680851 (3690 4360);
PAINT MONO (3690 4360);
FORCEPROP 0 LASTPIN (3700 5150) $PN I4
J 2
(3690 5160);
DISPLAY 0.680851 (3690 5160);
PAINT MONO (3690 5160);
FORCEPROP 0 LASTPIN (3700 2700) $PN J1
J 2
(3690 2710);
DISPLAY 0.680851 (3690 2710);
PAINT MONO (3690 2710);
FORCEPROP 0 LASTPIN (3700 3500) $PN J2
J 2
(3690 3510);
DISPLAY 0.680851 (3690 3510);
PAINT MONO (3690 3510);
FORCEPROP 0 LASTPIN (3700 4300) $PN J3
J 2
(3690 4310);
DISPLAY 0.680851 (3690 4310);
PAINT MONO (3690 4310);
FORCEPROP 0 LASTPIN (3700 5100) $PN J4
J 2
(3690 5110);
DISPLAY 0.680851 (3690 5110);
PAINT MONO (3690 5110);
FORCEPROP 0 LASTPIN (3700 2650) $PN K1
J 2
(3690 2660);
DISPLAY 0.680851 (3690 2660);
PAINT MONO (3690 2660);
FORCEPROP 0 LASTPIN (3700 3450) $PN K2
J 2
(3690 3460);
DISPLAY 0.680851 (3690 3460);
PAINT MONO (3690 3460);
FORCEPROP 0 LASTPIN (3700 4250) $PN K3
J 2
(3690 4260);
DISPLAY 0.680851 (3690 4260);
PAINT MONO (3690 4260);
FORCEPROP 0 LASTPIN (3700 5050) $PN K4
J 2
(3690 5060);
DISPLAY 0.680851 (3690 5060);
PAINT MONO (3690 5060);
FORCEPROP 0 LASTPIN (3700 2600) $PN L1
J 2
(3690 2610);
DISPLAY 0.680851 (3690 2610);
PAINT MONO (3690 2610);
FORCEPROP 0 LASTPIN (3700 3400) $PN L2
J 2
(3690 3410);
DISPLAY 0.680851 (3690 3410);
PAINT MONO (3690 3410);
FORCEPROP 0 LASTPIN (3700 4200) $PN L3
J 2
(3690 4210);
DISPLAY 0.680851 (3690 4210);
PAINT MONO (3690 4210);
FORCEPROP 0 LASTPIN (3700 5000) $PN L4
J 2
(3690 5010);
DISPLAY 0.680851 (3690 5010);
PAINT MONO (3690 5010);
FORCEPROP 0 LASTPIN (3700 2550) $PN M1
J 2
(3690 2560);
DISPLAY 0.680851 (3690 2560);
PAINT MONO (3690 2560);
FORCEPROP 0 LASTPIN (3700 3350) $PN M2
J 2
(3690 3360);
DISPLAY 0.680851 (3690 3360);
PAINT MONO (3690 3360);
FORCEPROP 0 LASTPIN (3700 4150) $PN M3
J 2
(3690 4160);
DISPLAY 0.680851 (3690 4160);
PAINT MONO (3690 4160);
FORCEPROP 0 LASTPIN (3700 4950) $PN M4
J 2
(3690 4960);
DISPLAY 0.680851 (3690 4960);
PAINT MONO (3690 4960);
FORCEPROP 0 LASTPIN (3700 2500) $PN N1
J 2
(3690 2510);
DISPLAY 0.680851 (3690 2510);
PAINT MONO (3690 2510);
FORCEPROP 0 LASTPIN (3700 3300) $PN N2
J 2
(3690 3310);
DISPLAY 0.680851 (3690 3310);
PAINT MONO (3690 3310);
FORCEPROP 0 LASTPIN (3700 4100) $PN N3
J 2
(3690 4110);
DISPLAY 0.680851 (3690 4110);
PAINT MONO (3690 4110);
FORCEPROP 0 LASTPIN (3700 4900) $PN N4
J 2
(3690 4910);
DISPLAY 0.680851 (3690 4910);
PAINT MONO (3690 4910);
FORCEPROP 1 LAST CDS_LMAN_SYM_OUTLINE -775,1650,775,-1650
J 0
(4625 4050);
DISPLAY 0.468085 (4625 4050);
PAINT GREEN (4625 4050);
DISPLAY INVISIBLE (4625 4050);
FORCEPROP 1 LAST NEEDS_NO_SIZE TRUE
J 0
(4625 4050);
DISPLAY 0.723404 (4625 4050);
PAINT GREEN (4625 4050);
DISPLAY INVISIBLE (4625 4050);
FORCEPROP 2 LAST CDS_LIB pure_quanta
J 0
(4625 4050);
DISPLAY INVISIBLE (4625 4050);
FORCEPROP 0 LAST VALUE CONN112_10137002-101LF
J 0
(3875 5950);
DISPLAY 1.021277 (3875 5950);
DISPLAY INVISIBLE (3875 5950);
FORCEPROP 1 LAST PATH I65
J 0
(4625 4050);
DISPLAY 0.723404 (4625 4050);
PAINT GREEN (4625 4050);
DISPLAY INVISIBLE (4625 4050);
FORCEPROP 0 LAST $SEC 2
J 0
(3875 6000);
DISPLAY 0.680851 (3875 6000);
PAINT MONO (3875 6000);
DISPLAY INVISIBLE (3875 6000);
FORCEPROP 0 LAST CDS_SEC 2
J 0
(3875 6000);
DISPLAY 1.021277 (3875 6000);
DISPLAY INVISIBLE (3875 6000);
FORCEADD OFFPAGE..5
(2400 3700);
FORCEPROP 2 LAST $XR0 30 
J 0
(2176 3700);
DISPLAY 0.638298 (2176 3700);
PAINT MONO (2176 3700);
FORCEPROP 2 LAST CDS_LIB standard
J 0
(2400 3700);
DISPLAY INVISIBLE (2400 3700);
FORCEPROP 1 LAST COMMENT_BODY TRUE
J 0
(2500 3625);
DISPLAY 1.170213 (2500 3625);
PAINT GREEN (2500 3625);
DISPLAY INVISIBLE (2500 3625);
FORCEPROP 1 LAST OFFPAGE TRUE
J 0
(2725 3575);
DISPLAY 0.872340 (2725 3575);
PAINT AQUA (2725 3575);
DISPLAY INVISIBLE (2725 3575);
FORCEPROP 2 LAST PATH I66
J 0
(2450 3775);
DISPLAY 1.021277 (2450 3775);
DISPLAY INVISIBLE (2450 3775);
FORCEADD OFFPAGE..2
R 2
(2400 3750);
FORCEPROP 2 LAST $XR0 30 
J 0
(2176 3750);
DISPLAY 0.638298 (2176 3750);
PAINT MONO (2176 3750);
FORCEPROP 2 LAST CDS_LIB standard
J 0
(2400 3750);
DISPLAY INVISIBLE (2400 3750);
FORCEPROP 1 LAST COMMENT_BODY TRUE
J 2
(2445 3655);
DISPLAY 0.872340 (2445 3655);
PAINT GREEN (2445 3655);
DISPLAY INVISIBLE (2445 3655);
FORCEPROP 1 LAST OFFPAGE TRUE
J 2
(2075 3625);
DISPLAY 0.872340 (2075 3625);
PAINT AQUA (2075 3625);
DISPLAY INVISIBLE (2075 3625);
FORCEPROP 2 LAST PATH I67
J 0
(2450 3825);
DISPLAY 1.021277 (2450 3825);
DISPLAY INVISIBLE (2450 3825);
FORCEADD CONN112_10137002101LF..1
(0 4125);
FORCEPROP 1 LAST PART_NUMBER DFHSB2FR012
J 0
(-750 5875);
DISPLAY 0.723404 (-750 5875);
PAINT GREEN (-750 5875);
DISPLAY INVISIBLE (-750 5875);
FORCEPROP 1 LAST MATERIAL IO
J 0
(-745 5807);
DISPLAY 0.723404 (-745 5807);
PAINT GREEN (-745 5807);
FORCEPROP 2 LAST PART_TYPE THLF
J 0
(-750 6000);
DISPLAY 1.021277 (-750 6000);
FORCEPROP 1 LAST LOCATION J106
J 0
(-750 5925);
DISPLAY 0.723404 (-750 5925);
PAINT GREEN (-750 5925);
FORCEPROP 0 LASTPIN (-925 3225) $PN A5
J 2
(-935 3235);
DISPLAY 0.680851 (-935 3235);
PAINT MONO (-935 3235);
FORCEPROP 0 LASTPIN (-925 4025) $PN A6
J 2
(-935 4035);
DISPLAY 0.680851 (-935 4035);
PAINT MONO (-935 4035);
FORCEPROP 0 LASTPIN (-925 4825) $PN A7
J 2
(-935 4835);
DISPLAY 0.680851 (-935 4835);
PAINT MONO (-935 4835);
FORCEPROP 0 LASTPIN (-925 5625) $PN A8
J 2
(-935 5635);
DISPLAY 0.680851 (-935 5635);
PAINT MONO (-935 5635);
FORCEPROP 0 LASTPIN (-925 3175) $PN B5
J 2
(-935 3185);
DISPLAY 0.680851 (-935 3185);
PAINT MONO (-935 3185);
FORCEPROP 0 LASTPIN (-925 3975) $PN B6
J 2
(-935 3985);
DISPLAY 0.680851 (-935 3985);
PAINT MONO (-935 3985);
FORCEPROP 0 LASTPIN (-925 4775) $PN B7
J 2
(-935 4785);
DISPLAY 0.680851 (-935 4785);
PAINT MONO (-935 4785);
FORCEPROP 0 LASTPIN (-925 5575) $PN B8
J 2
(-935 5585);
DISPLAY 0.680851 (-935 5585);
PAINT MONO (-935 5585);
FORCEPROP 0 LASTPIN (-925 3125) $PN C5
J 2
(-935 3135);
DISPLAY 0.680851 (-935 3135);
PAINT MONO (-935 3135);
FORCEPROP 0 LASTPIN (-925 3925) $PN C6
J 2
(-935 3935);
DISPLAY 0.680851 (-935 3935);
PAINT MONO (-935 3935);
FORCEPROP 0 LASTPIN (-925 4725) $PN C7
J 2
(-935 4735);
DISPLAY 0.680851 (-935 4735);
PAINT MONO (-935 4735);
FORCEPROP 0 LASTPIN (-925 5525) $PN C8
J 2
(-935 5535);
DISPLAY 0.680851 (-935 5535);
PAINT MONO (-935 5535);
FORCEPROP 0 LASTPIN (-925 3075) $PN D5
J 2
(-935 3085);
DISPLAY 0.680851 (-935 3085);
PAINT MONO (-935 3085);
FORCEPROP 0 LASTPIN (-925 3875) $PN D6
J 2
(-935 3885);
DISPLAY 0.680851 (-935 3885);
PAINT MONO (-935 3885);
FORCEPROP 0 LASTPIN (-925 4675) $PN D7
J 2
(-935 4685);
DISPLAY 0.680851 (-935 4685);
PAINT MONO (-935 4685);
FORCEPROP 0 LASTPIN (-925 5475) $PN D8
J 2
(-935 5485);
DISPLAY 0.680851 (-935 5485);
PAINT MONO (-935 5485);
FORCEPROP 0 LASTPIN (-925 3025) $PN E5
J 2
(-935 3035);
DISPLAY 0.680851 (-935 3035);
PAINT MONO (-935 3035);
FORCEPROP 0 LASTPIN (-925 3825) $PN E6
J 2
(-935 3835);
DISPLAY 0.680851 (-935 3835);
PAINT MONO (-935 3835);
FORCEPROP 0 LASTPIN (-925 4625) $PN E7
J 2
(-935 4635);
DISPLAY 0.680851 (-935 4635);
PAINT MONO (-935 4635);
FORCEPROP 0 LASTPIN (-925 5425) $PN E8
J 2
(-935 5435);
DISPLAY 0.680851 (-935 5435);
PAINT MONO (-935 5435);
FORCEPROP 0 LASTPIN (-925 2975) $PN F5
J 2
(-935 2985);
DISPLAY 0.680851 (-935 2985);
PAINT MONO (-935 2985);
FORCEPROP 0 LASTPIN (-925 3775) $PN F6
J 2
(-935 3785);
DISPLAY 0.680851 (-935 3785);
PAINT MONO (-935 3785);
FORCEPROP 0 LASTPIN (-925 4575) $PN F7
J 2
(-935 4585);
DISPLAY 0.680851 (-935 4585);
PAINT MONO (-935 4585);
FORCEPROP 0 LASTPIN (-925 5375) $PN F8
J 2
(-935 5385);
DISPLAY 0.680851 (-935 5385);
PAINT MONO (-935 5385);
FORCEPROP 0 LASTPIN (-925 2925) $PN G5
J 2
(-935 2935);
DISPLAY 0.680851 (-935 2935);
PAINT MONO (-935 2935);
FORCEPROP 0 LASTPIN (-925 3725) $PN G6
J 2
(-935 3735);
DISPLAY 0.680851 (-935 3735);
PAINT MONO (-935 3735);
FORCEPROP 0 LASTPIN (-925 4525) $PN G7
J 2
(-935 4535);
DISPLAY 0.680851 (-935 4535);
PAINT MONO (-935 4535);
FORCEPROP 0 LASTPIN (-925 5325) $PN G8
J 2
(-935 5335);
DISPLAY 0.680851 (-935 5335);
PAINT MONO (-935 5335);
FORCEPROP 0 LASTPIN (-925 2875) $PN H5
J 2
(-935 2885);
DISPLAY 0.680851 (-935 2885);
PAINT MONO (-935 2885);
FORCEPROP 0 LASTPIN (-925 3675) $PN H6
J 2
(-935 3685);
DISPLAY 0.680851 (-935 3685);
PAINT MONO (-935 3685);
FORCEPROP 0 LASTPIN (-925 4475) $PN H7
J 2
(-935 4485);
DISPLAY 0.680851 (-935 4485);
PAINT MONO (-935 4485);
FORCEPROP 0 LASTPIN (-925 5275) $PN H8
J 2
(-935 5285);
DISPLAY 0.680851 (-935 5285);
PAINT MONO (-935 5285);
FORCEPROP 0 LASTPIN (-925 2825) $PN I5
J 2
(-935 2835);
DISPLAY 0.680851 (-935 2835);
PAINT MONO (-935 2835);
FORCEPROP 0 LASTPIN (-925 3625) $PN I6
J 2
(-935 3635);
DISPLAY 0.680851 (-935 3635);
PAINT MONO (-935 3635);
FORCEPROP 0 LASTPIN (-925 4425) $PN I7
J 2
(-935 4435);
DISPLAY 0.680851 (-935 4435);
PAINT MONO (-935 4435);
FORCEPROP 0 LASTPIN (-925 5225) $PN I8
J 2
(-935 5235);
DISPLAY 0.680851 (-935 5235);
PAINT MONO (-935 5235);
FORCEPROP 0 LASTPIN (-925 2775) $PN J5
J 2
(-935 2785);
DISPLAY 0.680851 (-935 2785);
PAINT MONO (-935 2785);
FORCEPROP 0 LASTPIN (-925 3575) $PN J6
J 2
(-935 3585);
DISPLAY 0.680851 (-935 3585);
PAINT MONO (-935 3585);
FORCEPROP 0 LASTPIN (-925 4375) $PN J7
J 2
(-935 4385);
DISPLAY 0.680851 (-935 4385);
PAINT MONO (-935 4385);
FORCEPROP 0 LASTPIN (-925 5175) $PN J8
J 2
(-935 5185);
DISPLAY 0.680851 (-935 5185);
PAINT MONO (-935 5185);
FORCEPROP 0 LASTPIN (-925 2725) $PN K5
J 2
(-935 2735);
DISPLAY 0.680851 (-935 2735);
PAINT MONO (-935 2735);
FORCEPROP 0 LASTPIN (-925 3525) $PN K6
J 2
(-935 3535);
DISPLAY 0.680851 (-935 3535);
PAINT MONO (-935 3535);
FORCEPROP 0 LASTPIN (-925 4325) $PN K7
J 2
(-935 4335);
DISPLAY 0.680851 (-935 4335);
PAINT MONO (-935 4335);
FORCEPROP 0 LASTPIN (-925 5125) $PN K8
J 2
(-935 5135);
DISPLAY 0.680851 (-935 5135);
PAINT MONO (-935 5135);
FORCEPROP 0 LASTPIN (-925 2675) $PN L5
J 2
(-935 2685);
DISPLAY 0.680851 (-935 2685);
PAINT MONO (-935 2685);
FORCEPROP 0 LASTPIN (-925 3475) $PN L6
J 2
(-935 3485);
DISPLAY 0.680851 (-935 3485);
PAINT MONO (-935 3485);
FORCEPROP 0 LASTPIN (-925 4275) $PN L7
J 2
(-935 4285);
DISPLAY 0.680851 (-935 4285);
PAINT MONO (-935 4285);
FORCEPROP 0 LASTPIN (-925 5075) $PN L8
J 2
(-935 5085);
DISPLAY 0.680851 (-935 5085);
PAINT MONO (-935 5085);
FORCEPROP 0 LASTPIN (-925 2625) $PN M5
J 2
(-935 2635);
DISPLAY 0.680851 (-935 2635);
PAINT MONO (-935 2635);
FORCEPROP 0 LASTPIN (-925 3425) $PN M6
J 2
(-935 3435);
DISPLAY 0.680851 (-935 3435);
PAINT MONO (-935 3435);
FORCEPROP 0 LASTPIN (-925 4225) $PN M7
J 2
(-935 4235);
DISPLAY 0.680851 (-935 4235);
PAINT MONO (-935 4235);
FORCEPROP 0 LASTPIN (-925 5025) $PN M8
J 2
(-935 5035);
DISPLAY 0.680851 (-935 5035);
PAINT MONO (-935 5035);
FORCEPROP 0 LASTPIN (-925 2575) $PN N5
J 2
(-935 2585);
DISPLAY 0.680851 (-935 2585);
PAINT MONO (-935 2585);
FORCEPROP 0 LASTPIN (-925 3375) $PN N6
J 2
(-935 3385);
DISPLAY 0.680851 (-935 3385);
PAINT MONO (-935 3385);
FORCEPROP 0 LASTPIN (-925 4175) $PN N7
J 2
(-935 4185);
DISPLAY 0.680851 (-935 4185);
PAINT MONO (-935 4185);
FORCEPROP 0 LASTPIN (-925 4975) $PN N8
J 2
(-935 4985);
DISPLAY 0.680851 (-935 4985);
PAINT MONO (-935 4985);
FORCEPROP 1 LAST PATH I68
J 0
(0 4125);
DISPLAY 0.723404 (0 4125);
PAINT GREEN (0 4125);
DISPLAY INVISIBLE (0 4125);
FORCEPROP 2 LAST CDS_LIB pure_quanta
J 0
(0 4125);
DISPLAY INVISIBLE (0 4125);
FORCEPROP 1 LAST NEEDS_NO_SIZE TRUE
J 0
(0 4125);
DISPLAY 0.723404 (0 4125);
PAINT GREEN (0 4125);
DISPLAY INVISIBLE (0 4125);
FORCEPROP 1 LAST CDS_LMAN_SYM_OUTLINE -775,1650,775,-1650
J 0
(0 4125);
DISPLAY 0.468085 (0 4125);
PAINT GREEN (0 4125);
DISPLAY INVISIBLE (0 4125);
FORCEPROP 0 LAST VALUE CONN112_10137002-101LF
J 0
(-725 6125);
DISPLAY 1.021277 (-725 6125);
DISPLAY INVISIBLE (-725 6125);
FORCEPROP 0 LAST $SEC 1
J 0
(-750 6050);
DISPLAY 0.680851 (-750 6050);
PAINT MONO (-750 6050);
DISPLAY INVISIBLE (-750 6050);
FORCEPROP 0 LAST CDS_SEC 1
J 0
(-750 6050);
DISPLAY 1.021277 (-750 6050);
DISPLAY INVISIBLE (-750 6050);
FORCEADD OFFPAGE..1
(-2200 3475);
FORCEPROP 2 LAST $XR0 173 
J 0
(-2452 3475);
DISPLAY 0.638298 (-2452 3475);
PAINT MONO (-2452 3475);
FORCEPROP 2 LAST PATH I7
J 0
(-2150 3550);
DISPLAY 1.021277 (-2150 3550);
DISPLAY INVISIBLE (-2150 3550);
FORCEPROP 1 LAST OFFPAGE TRUE
J 0
(-1875 3350);
DISPLAY 0.872340 (-1875 3350);
PAINT AQUA (-1875 3350);
DISPLAY INVISIBLE (-1875 3350);
FORCEPROP 1 LAST COMMENT_BODY TRUE
J 0
(-2075 3375);
DISPLAY 0.872340 (-2075 3375);
PAINT GREEN (-2075 3375);
DISPLAY INVISIBLE (-2075 3375);
FORCEPROP 2 LAST CDS_LIB standard
J 0
(-2200 3475);
DISPLAY INVISIBLE (-2200 3475);
FORCEADD OFFPAGE..2
R 2
(-2200 3125);
FORCEPROP 2 LAST $XR0 30 
J 0
(-2454 3125);
DISPLAY 0.638298 (-2454 3125);
PAINT MONO (-2454 3125);
FORCEPROP 2 LAST PATH I8
J 0
(-2150 3200);
DISPLAY 1.021277 (-2150 3200);
DISPLAY INVISIBLE (-2150 3200);
FORCEPROP 2 LAST CDS_LIB standard
J 0
(-2200 3125);
DISPLAY INVISIBLE (-2200 3125);
FORCEPROP 1 LAST COMMENT_BODY TRUE
J 2
(-2155 3030);
DISPLAY 0.872340 (-2155 3030);
PAINT GREEN (-2155 3030);
DISPLAY INVISIBLE (-2155 3030);
FORCEPROP 1 LAST OFFPAGE TRUE
J 2
(-2525 3000);
DISPLAY 0.872340 (-2525 3000);
PAINT AQUA (-2525 3000);
DISPLAY INVISIBLE (-2525 3000);
FORCEADD OFFPAGE..2
R 2
(2400 4750);
FORCEPROP 2 LAST $XR0 148 
J 0
(2145 4750);
DISPLAY 0.638298 (2145 4750);
PAINT MONO (2145 4750);
FORCEPROP 2 LAST PATH I82
J 0
(2125 4800);
DISPLAY 1.021277 (2125 4800);
DISPLAY INVISIBLE (2125 4800);
FORCEPROP 1 LAST COMMENT_BODY TRUE
J 2
(2445 4655);
DISPLAY 0.872340 (2445 4655);
PAINT GREEN (2445 4655);
DISPLAY INVISIBLE (2445 4655);
FORCEPROP 1 LAST OFFPAGE TRUE
J 2
(2075 4625);
DISPLAY 0.872340 (2075 4625);
PAINT AQUA (2075 4625);
DISPLAY INVISIBLE (2075 4625);
FORCEPROP 2 LAST CDS_LIB standard
J 0
(2400 4750);
DISPLAY INVISIBLE (2400 4750);
FORCEADD OFFPAGE..4
R 2
(-2200 4975);
FORCEPROP 2 LAST $XR0 240 
J 0
(-2452 4975);
DISPLAY 0.638298 (-2452 4975);
PAINT MONO (-2452 4975);
FORCEPROP 2 LAST PATH I85
J 0
(-2450 5025);
DISPLAY 1.021277 (-2450 5025);
DISPLAY INVISIBLE (-2450 5025);
FORCEPROP 2 LAST CDS_LIB standard
J 0
(-2200 4975);
DISPLAY INVISIBLE (-2200 4975);
FORCEPROP 1 LAST OFFPAGE TRUE
J 2
(-2525 4850);
DISPLAY 0.872340 (-2525 4850);
PAINT GREEN (-2525 4850);
DISPLAY INVISIBLE (-2525 4850);
FORCEPROP 1 LAST COMMENT_BODY TRUE
J 2
(-2175 4875);
DISPLAY 0.872340 (-2175 4875);
PAINT GREEN (-2175 4875);
DISPLAY INVISIBLE (-2175 4875);
FORCEADD OFFPAGE..5
(-2225 3375);
FORCEPROP 2 LAST $XR0 151 
J 0
(-2480 3375);
DISPLAY 0.638298 (-2480 3375);
PAINT MONO (-2480 3375);
FORCEPROP 2 LAST PATH I86
J 0
(-2500 3425);
DISPLAY 1.021277 (-2500 3425);
DISPLAY INVISIBLE (-2500 3425);
FORCEPROP 2 LAST CDS_LIB standard
J 0
(-2225 3375);
DISPLAY INVISIBLE (-2225 3375);
FORCEPROP 1 LAST OFFPAGE TRUE
J 0
(-1900 3250);
DISPLAY 0.872340 (-1900 3250);
PAINT AQUA (-1900 3250);
DISPLAY INVISIBLE (-1900 3250);
FORCEPROP 1 LAST COMMENT_BODY TRUE
J 0
(-2125 3300);
DISPLAY 1.170213 (-2125 3300);
PAINT GREEN (-2125 3300);
DISPLAY INVISIBLE (-2125 3300);
FORCEADD OFFPAGE..3
R 2
(2400 4900);
FORCEPROP 2 LAST $XR0 234 
J 0
(2120 4900);
DISPLAY 0.638298 (2120 4900);
PAINT MONO (2120 4900);
FORCEPROP 1 LAST COMMENT_BODY TRUE
J 2
(2450 4800);
DISPLAY 0.872340 (2450 4800);
PAINT GREEN (2450 4800);
DISPLAY INVISIBLE (2450 4800);
FORCEPROP 1 LAST OFFPAGE TRUE
J 2
(2075 4775);
DISPLAY 0.872340 (2075 4775);
DISPLAY INVISIBLE (2075 4775);
FORCEPROP 2 LAST CDS_LIB standard
J 0
(2400 4900);
DISPLAY INVISIBLE (2400 4900);
FORCEPROP 2 LAST PATH I88
J 0
(2125 4950);
DISPLAY 1.021277 (2125 4950);
DISPLAY INVISIBLE (2125 4950);
FORCEADD OFFPAGE..4
R 2
(2400 3300);
FORCEPROP 2 LAST $XR0 234 
J 0
(2148 3300);
DISPLAY 0.638298 (2148 3300);
PAINT MONO (2148 3300);
FORCEPROP 1 LAST OFFPAGE TRUE
J 2
(2075 3175);
DISPLAY 0.872340 (2075 3175);
PAINT GREEN (2075 3175);
DISPLAY INVISIBLE (2075 3175);
FORCEPROP 1 LAST COMMENT_BODY TRUE
J 2
(2425 3200);
DISPLAY 0.872340 (2425 3200);
PAINT GREEN (2425 3200);
DISPLAY INVISIBLE (2425 3200);
FORCEPROP 2 LAST CDS_LIB standard
J 0
(2400 3300);
DISPLAY INVISIBLE (2400 3300);
FORCEPROP 2 LAST PATH I89
J 0
(2125 3350);
DISPLAY 1.021277 (2125 3350);
DISPLAY INVISIBLE (2125 3350);
FORCEADD OFFPAGE..5
(-2200 3075);
FORCEPROP 2 LAST $XR0 30 
J 0
(-2454 3075);
DISPLAY 0.638298 (-2454 3075);
PAINT MONO (-2454 3075);
FORCEPROP 2 LAST PATH I9
J 0
(-2150 3150);
DISPLAY 1.021277 (-2150 3150);
DISPLAY INVISIBLE (-2150 3150);
FORCEPROP 2 LAST CDS_LIB standard
J 0
(-2200 3075);
DISPLAY INVISIBLE (-2200 3075);
FORCEPROP 1 LAST COMMENT_BODY TRUE
J 0
(-2100 3000);
DISPLAY 1.170213 (-2100 3000);
PAINT GREEN (-2100 3000);
DISPLAY INVISIBLE (-2100 3000);
FORCEPROP 1 LAST OFFPAGE TRUE
J 0
(-1875 2950);
DISPLAY 0.872340 (-1875 2950);
PAINT AQUA (-1875 2950);
DISPLAY INVISIBLE (-1875 2950);
FORCEADD OFFPAGE..5
(-2200 4825);
FORCEPROP 2 LAST $XR0 146 
J 0
(-2485 4825);
DISPLAY 0.638298 (-2485 4825);
PAINT MONO (-2485 4825);
FORCEPROP 1 LAST OFFPAGE TRUE
J 0
(-1875 4700);
DISPLAY 0.872340 (-1875 4700);
PAINT AQUA (-1875 4700);
DISPLAY INVISIBLE (-1875 4700);
FORCEPROP 1 LAST COMMENT_BODY TRUE
J 0
(-2100 4750);
DISPLAY 1.170213 (-2100 4750);
PAINT GREEN (-2100 4750);
DISPLAY INVISIBLE (-2100 4750);
FORCEPROP 2 LAST CDS_LIB standard
J 0
(-2200 4825);
DISPLAY INVISIBLE (-2200 4825);
FORCEPROP 2 LAST PATH I90
J 0
(-2450 4875);
DISPLAY 1.021277 (-2450 4875);
DISPLAY INVISIBLE (-2450 4875);
FORCEADD OFFPAGE..2
R 2
(2375 3150);
FORCEPROP 2 LAST $XR0 144 
J 0
(2120 3150);
DISPLAY 0.638298 (2120 3150);
PAINT MONO (2120 3150);
FORCEPROP 2 LAST CDS_LIB standard
J 0
(2375 3150);
DISPLAY INVISIBLE (2375 3150);
FORCEPROP 2 LAST PATH I91
J 0
(2425 3225);
DISPLAY 1.021277 (2425 3225);
DISPLAY INVISIBLE (2425 3225);
FORCEPROP 1 LAST COMMENT_BODY TRUE
J 2
(2420 3055);
DISPLAY 0.872340 (2420 3055);
PAINT GREEN (2420 3055);
DISPLAY INVISIBLE (2420 3055);
FORCEPROP 1 LAST OFFPAGE TRUE
J 2
(2050 3025);
DISPLAY 0.872340 (2050 3025);
PAINT AQUA (2050 3025);
DISPLAY INVISIBLE (2050 3025);
FORCEADD QUANTA_TITLE_BLOCK_C..1
(5775 400);
FORCEPROP 0 LAST CDS_CON_LAST_MODIFIED Fri Aug 25 14:01:58 2023
J 0
(3890 415);
PAINT MONO (3890 415);
DISPLAY INVISIBLE (3890 415);
FORCEPROP 2 LAST CUSTOM_TXT_CDS <XR_PAGE_TITLE>
J 0
(-2115 5650);
DISPLAY 0.638298 (-2115 5650);
PAINT PINK (-2115 5650);
DISPLAY INVISIBLE (-2115 5650);
FORCEPROP 2 LAST CUSTOM_TXT_CDS <CON_PAGE_NUM> OF <CON_TOTAL_PAGES>
J 0
(5250 425);
DISPLAY 0.978723 (5250 425);
FORCEPROP 2 LAST CUSTOM_TXT_CDS <CON_LAST_MODIFIED>
J 0
(3875 400);
DISPLAY 0.978723 (3875 400);
FORCEPROP 2 LAST CUSTOM_TXT_CDS <Q_NUMBER>
J 0
(4372 503);
DISPLAY 1.212766 (4372 503);
FORCEPROP 2 LAST CUSTOM_TXT_CDS <Q_REV>
J 0
(5591 503);
DISPLAY 1.212766 (5591 503);
FORCEPROP 2 LAST CUSTOM_TXT_CDS <Q_PROJ>
J 0
(3393 502);
DISPLAY 1.212766 (3393 502);
FORCEPROP 2 LAST CUSTOM_TXT_CDS <NAME_1>
J 0
(2600 575);
FORCEPROP 2 LAST CUSTOM_TXT_CDS <NAME_2>
J 0
(2600 450);
FORCEPROP 1 LAST Q_TITLE PCIE - CPU0_EXAMAX_P2/P3_X16
J 0
(-3500 450);
DISPLAY 1.957447 (-3500 450);
PAINT GREEN (-3500 450);
FORCEPROP 1 LAST Q_DEPT 
J 1
(2012 449);
DISPLAY 1.957447 (2012 449);
PAINT GREEN (2012 449);
FORCEPROP 2 LAST CDS_XR_PAGE_TITLE CR-137 : @S9S_MB_2U_LIB.S9S_MB_2U(SCH_1):PAGE137
J 0
(-2115 5650);
DISPLAY 0.638298 (-2115 5650);
PAINT PINK (-2115 5650);
DISPLAY INVISIBLE (-2115 5650);
FORCEPROP 2 LAST CDS_LIB pure_quanta
J 0
(5775 400);
PAINT MONO (5775 400);
DISPLAY INVISIBLE (5775 400);
FORCEPROP 1 LAST CDS_LMAN_SYM_OUTLINE -9475,6775,100,-125
J 0
(5775 400);
DISPLAY 0.468085 (5775 400);
PAINT GREEN (5775 400);
DISPLAY INVISIBLE (5775 400);
FORCEPROP 2 LAST PAGE_BORDER TRUE
J 0
(-2115 5650);
DISPLAY 0.638298 (-2115 5650);
PAINT PINK (-2115 5650);
DISPLAY INVISIBLE (-2115 5650);
FORCEPROP 1 LAST COMMENT_BODY TRUE
J 0
(5787 387);
DISPLAY 0.978723 (5787 387);
PAINT GREEN (5787 387);
DISPLAY INVISIBLE (5787 387);
WIRE 16 -1 (3475 2500)(3475 2150);
WIRE 16 -1 (3475 2650)(3475 2500);
WIRE 16 -1 (3700 2500)(3475 2500);
WIRE 16 -1 (-1100 2575)(-1100 2275);
WIRE 16 -1 (-1100 2725)(-1100 2575);
WIRE 16 -1 (-925 2575)(-1100 2575);
WIRE 16 -1 (-925 4675)(-2150 4675);
FORCEPROP 2 LAST SIG_NAME P5E_CPU0_PE3_RX_DP<9>
J 0
(-2035 4685);
DISPLAY 0.638298 (-2035 4685);
WIRE 16 -1 (-925 4575)(-2150 4575);
FORCEPROP 2 LAST SIG_NAME P5E_CPU0_PE2_RX_DP<9>
J 0
(-2035 4585);
DISPLAY 0.638298 (-2035 4585);
WIRE 16 -1 (-925 4525)(-2150 4525);
FORCEPROP 2 LAST SIG_NAME P5E_CPU0_PE2_RX_DN<9>
J 0
(-2035 4535);
DISPLAY 0.638298 (-2035 4535);
WIRE 16 -1 (-925 4375)(-2150 4375);
FORCEPROP 2 LAST SIG_NAME P5E_CPU0_PE3_TX_C_DP<9>
J 0
(-2035 4385);
DISPLAY 0.638298 (-2035 4385);
WIRE 16 -1 (-925 4725)(-2150 4725);
FORCEPROP 2 LAST SIG_NAME P5E_CPU0_PE3_RX_DN<9>
J 0
(-2035 4735);
DISPLAY 0.638298 (-2035 4735);
WIRE 16 -1 (-925 5625)(-1100 5625);
WIRE 16 -1 (-1100 5625)(-1100 5475);
WIRE 16 -1 (-925 5475)(-1100 5475);
WIRE 16 -1 (-1100 5475)(-1100 5325);
WIRE 16 -1 (-925 5325)(-1100 5325);
WIRE 16 -1 (-1100 5325)(-1100 5175);
WIRE 16 -1 (-925 5175)(-1100 5175);
WIRE 16 -1 (-1100 5175)(-1100 5025);
WIRE 16 -1 (-925 5025)(-1100 5025);
WIRE 16 -1 (-1100 5025)(-1100 4775);
WIRE 16 -1 (-925 4775)(-1100 4775);
WIRE 16 -1 (-1100 4775)(-1100 4625);
WIRE 16 -1 (-925 4625)(-1100 4625);
WIRE 16 -1 (-1100 4625)(-1100 4475);
WIRE 16 -1 (-925 4475)(-1100 4475);
WIRE 16 -1 (-1100 4475)(-1100 4325);
WIRE 16 -1 (-925 4325)(-1100 4325);
WIRE 16 -1 (-1100 4325)(-1100 4175);
WIRE 16 -1 (-925 4175)(-1100 4175);
WIRE 16 -1 (-925 4025)(-1100 4025);
WIRE 16 -1 (-1100 4175)(-1100 4025);
WIRE 16 -1 (-1100 4025)(-1100 3875);
WIRE 16 -1 (-925 3875)(-1100 3875);
WIRE 16 -1 (-1100 3875)(-1100 3725);
WIRE 16 -1 (-925 3725)(-1100 3725);
WIRE 16 -1 (-1100 3725)(-1100 3575);
WIRE 16 -1 (-925 3575)(-1100 3575);
WIRE 16 -1 (-1100 3575)(-1100 3425);
WIRE 16 -1 (-925 3425)(-1100 3425);
WIRE 16 -1 (-1100 3425)(-1100 3175);
WIRE 16 -1 (-925 3175)(-1100 3175);
WIRE 16 -1 (-1100 3025)(-1100 3175);
WIRE 16 -1 (-925 3025)(-1100 3025);
WIRE 16 -1 (-1100 2875)(-1100 3025);
WIRE 16 -1 (-925 2875)(-1100 2875);
WIRE 16 -1 (-1100 2875)(-1100 2725);
WIRE 16 -1 (-925 2725)(-1100 2725);
WIRE 16 -1 (-925 4825)(-2150 4825);
FORCEPROP 2 LAST SIG_NAME PRSNT_CABLE_GPU_A1_N
J 0
(-2035 4835);
DISPLAY 0.638298 (-2035 4835);
WIRE 16 -1 (-925 4275)(-2150 4275);
FORCEPROP 2 LAST SIG_NAME P5E_CPU0_PE2_TX_C_DP<9>
J 0
(-2035 4285);
DISPLAY 0.638298 (-2035 4285);
WIRE 16 -1 (-925 4225)(-2150 4225);
FORCEPROP 2 LAST SIG_NAME P5E_CPU0_PE2_TX_C_DN<9>
J 0
(-2035 4235);
DISPLAY 0.638298 (-2035 4235);
WIRE 16 -1 (-925 4425)(-2150 4425);
FORCEPROP 2 LAST SIG_NAME P5E_CPU0_PE3_TX_C_DN<9>
J 0
(-2035 4435);
DISPLAY 0.638298 (-2035 4435);
WIRE 16 -1 (3700 3150)(2425 3150);
FORCEPROP 2 LAST SIG_NAME PRSNT_CABLE_SWB_B1_N
J 0
(2565 3160);
DISPLAY 0.638298 (2565 3160);
WIRE 16 -1 (3700 3050)(2450 3050);
FORCEPROP 2 LAST SIG_NAME P5E_CPU0_PE3_RX_DP<15>
J 0
(2565 3060);
DISPLAY 0.638298 (2565 3060);
WIRE 16 -1 (3700 3000)(2450 3000);
FORCEPROP 2 LAST SIG_NAME P5E_CPU0_PE3_RX_DN<15>
J 0
(2565 3010);
DISPLAY 0.638298 (2565 3010);
WIRE 16 -1 (3700 2900)(2450 2900);
FORCEPROP 2 LAST SIG_NAME P5E_CPU0_PE2_RX_DP<15>
J 0
(2565 2910);
DISPLAY 0.638298 (2565 2910);
WIRE 16 -1 (3700 2850)(2450 2850);
FORCEPROP 2 LAST SIG_NAME P5E_CPU0_PE2_RX_DN<15>
J 0
(2565 2860);
DISPLAY 0.638298 (2565 2860);
WIRE 16 -1 (3700 5550)(3475 5550);
WIRE 16 -1 (3475 5550)(3475 5400);
WIRE 16 -1 (3700 5400)(3475 5400);
WIRE 16 -1 (3475 5400)(3475 5250);
WIRE 16 -1 (3700 5250)(3475 5250);
WIRE 16 -1 (3700 5100)(3475 5100);
WIRE 16 -1 (3475 5250)(3475 5100);
WIRE 16 -1 (3475 5100)(3475 4950);
WIRE 16 -1 (3700 4950)(3475 4950);
WIRE 16 -1 (3475 4950)(3475 4700);
WIRE 16 -1 (3700 4700)(3475 4700);
WIRE 16 -1 (3475 4700)(3475 4550);
WIRE 16 -1 (3700 4550)(3475 4550);
WIRE 16 -1 (3475 4550)(3475 4400);
WIRE 16 -1 (3700 4400)(3475 4400);
WIRE 16 -1 (3475 4400)(3475 4250);
WIRE 16 -1 (3700 4250)(3475 4250);
WIRE 16 -1 (3475 4250)(3475 4100);
WIRE 16 -1 (3700 4100)(3475 4100);
WIRE 16 -1 (3700 3950)(3475 3950);
WIRE 16 -1 (3475 4100)(3475 3950);
WIRE 16 -1 (3475 3950)(3475 3800);
WIRE 16 -1 (3700 3800)(3475 3800);
WIRE 16 -1 (3475 3800)(3475 3650);
WIRE 16 -1 (3700 3650)(3475 3650);
WIRE 16 -1 (3475 3650)(3475 3500);
WIRE 16 -1 (3700 3500)(3475 3500);
WIRE 16 -1 (3475 3500)(3475 3350);
WIRE 16 -1 (3700 3350)(3475 3350);
WIRE 16 -1 (3475 3350)(3475 3100);
WIRE 16 -1 (3700 3100)(3475 3100);
WIRE 16 -1 (3700 2950)(3475 2950);
WIRE 16 -1 (3475 3100)(3475 2950);
WIRE 16 -1 (3475 2950)(3475 2800);
WIRE 16 -1 (3700 2800)(3475 2800);
WIRE 16 -1 (3475 2800)(3475 2650);
WIRE 16 -1 (3700 2650)(3475 2650);
WIRE 16 -1 (3700 2600)(2450 2600);
FORCEPROP 2 LAST SIG_NAME P5E_CPU0_PE2_TX_C_DN<15>
J 0
(2565 2610);
DISPLAY 0.638298 (2565 2610);
WIRE 16 -1 (3700 2700)(2450 2700);
FORCEPROP 2 LAST SIG_NAME P5E_CPU0_PE3_TX_C_DP<15>
J 0
(2565 2710);
DISPLAY 0.638298 (2565 2710);
WIRE 16 -1 (3700 3300)(2450 3300);
FORCEPROP 2 LAST SIG_NAME I3C_BMC_SWB_BUF_SDA
J 0
(2565 3310);
DISPLAY 0.638298 (2565 3310);
WIRE 16 -1 (3700 3400)(2450 3400);
FORCEPROP 2 LAST SIG_NAME P5E_CPU0_PE2_TX_C_DN<14>
J 0
(2565 3410);
DISPLAY 0.638298 (2565 3410);
WIRE 16 -1 (3700 3550)(2450 3550);
FORCEPROP 2 LAST SIG_NAME P5E_CPU0_PE3_TX_C_DP<14>
J 0
(2565 3560);
DISPLAY 0.638298 (2565 3560);
WIRE 16 -1 (3700 3600)(2450 3600);
FORCEPROP 2 LAST SIG_NAME P5E_CPU0_PE3_TX_C_DN<14>
J 0
(2565 3610);
DISPLAY 0.638298 (2565 3610);
WIRE 16 -1 (3700 3700)(2450 3700);
FORCEPROP 2 LAST SIG_NAME P5E_CPU0_PE2_RX_DN<14>
J 0
(2565 3710);
DISPLAY 0.638298 (2565 3710);
WIRE 16 -1 (3700 3750)(2450 3750);
FORCEPROP 2 LAST SIG_NAME P5E_CPU0_PE2_RX_DP<14>
J 0
(2565 3760);
DISPLAY 0.638298 (2565 3760);
WIRE 16 -1 (3700 4300)(2450 4300);
FORCEPROP 2 LAST SIG_NAME P5E_CPU0_PE3_TX_C_DP<13>
J 0
(2565 4310);
DISPLAY 0.638298 (2565 4310);
WIRE 16 -1 (3700 4350)(2450 4350);
FORCEPROP 2 LAST SIG_NAME P5E_CPU0_PE3_TX_C_DN<13>
J 0
(2565 4360);
DISPLAY 0.638298 (2565 4360);
WIRE 16 -1 (3700 4450)(2450 4450);
FORCEPROP 2 LAST SIG_NAME P5E_CPU0_PE2_RX_DN<13>
J 0
(2565 4460);
DISPLAY 0.638298 (2565 4460);
WIRE 16 -1 (3700 4900)(2450 4900);
FORCEPROP 2 LAST SIG_NAME I3C_BMC_SWB_BUF_SCL
J 0
(2565 4910);
DISPLAY 0.638298 (2565 4910);
WIRE 16 -1 (3700 4750)(2450 4750);
FORCEPROP 2 LAST SIG_NAME FM_SWB_PWRGD
J 0
(2565 4760);
DISPLAY 0.638298 (2565 4760);
WIRE 16 -1 (3700 4650)(2450 4650);
FORCEPROP 2 LAST SIG_NAME P5E_CPU0_PE3_RX_DP<13>
J 0
(2565 4660);
DISPLAY 0.638298 (2565 4660);
WIRE 16 -1 (3700 4600)(2450 4600);
FORCEPROP 2 LAST SIG_NAME P5E_CPU0_PE3_RX_DN<13>
J 0
(2565 4610);
DISPLAY 0.638298 (2565 4610);
WIRE 16 -1 (3700 4500)(2450 4500);
FORCEPROP 2 LAST SIG_NAME P5E_CPU0_PE2_RX_DP<13>
J 0
(2565 4510);
DISPLAY 0.638298 (2565 4510);
WIRE 16 -1 (3700 4200)(2450 4200);
FORCEPROP 2 LAST SIG_NAME P5E_CPU0_PE2_TX_C_DP<13>
J 0
(2565 4210);
DISPLAY 0.638298 (2565 4210);
WIRE 16 -1 (3700 3850)(2450 3850);
FORCEPROP 2 LAST SIG_NAME P5E_CPU0_PE3_RX_DN<14>
J 0
(2565 3860);
DISPLAY 0.638298 (2565 3860);
WIRE 16 -1 (-925 3925)(-2150 3925);
FORCEPROP 2 LAST SIG_NAME P5E_CPU0_PE3_RX_DP<10>
J 0
(-2035 3935);
DISPLAY 0.638298 (-2035 3935);
WIRE 16 -1 (-925 4975)(-2150 4975);
FORCEPROP 2 LAST SIG_NAME UART_BMC_BIC_TX
J 0
(-2035 4985);
DISPLAY 0.638298 (-2035 4985);
WIRE 16 -1 (-925 3775)(-2150 3775);
FORCEPROP 2 LAST SIG_NAME P5E_CPU0_PE2_RX_DN<10>
J 0
(-2035 3785);
DISPLAY 0.638298 (-2035 3785);
WIRE 16 -1 (-925 5075)(-2150 5075);
FORCEPROP 2 LAST SIG_NAME P5E_CPU0_PE2_TX_C_DN<8>
J 0
(-2035 5085);
DISPLAY 0.638298 (-2035 5085);
WIRE 16 -1 (-925 3075)(-2150 3075);
FORCEPROP 2 LAST SIG_NAME P5E_CPU0_PE3_RX_DP<11>
J 0
(-2035 3085);
DISPLAY 0.638298 (-2035 3085);
WIRE 16 -1 (-925 3125)(-2150 3125);
FORCEPROP 2 LAST SIG_NAME P5E_CPU0_PE3_RX_DN<11>
J 0
(-2035 3135);
DISPLAY 0.638298 (-2035 3135);
WIRE 16 -1 (-925 3375)(-2175 3375);
FORCEPROP 2 LAST SIG_NAME UART_BMC_BIC_RX
J 0
(-2035 3385);
DISPLAY 0.638298 (-2035 3385);
WIRE 16 -1 (-925 3225)(-2150 3225);
FORCEPROP 2 LAST SIG_NAME NC_J106_A5
J 0
(-2035 3235);
DISPLAY 0.638298 (-2035 3235);
WIRE 16 -1 (3700 3900)(2450 3900);
FORCEPROP 2 LAST SIG_NAME P5E_CPU0_PE3_RX_DP<14>
J 0
(2565 3910);
DISPLAY 0.638298 (2565 3910);
WIRE 16 -1 (3700 4150)(2450 4150);
FORCEPROP 2 LAST SIG_NAME P5E_CPU0_PE2_TX_C_DN<13>
J 0
(2565 4160);
DISPLAY 0.638298 (2565 4160);
WIRE 16 -1 (-925 2925)(-2150 2925);
FORCEPROP 2 LAST SIG_NAME P5E_CPU0_PE2_RX_DN<11>
J 0
(-2035 2935);
DISPLAY 0.638298 (-2035 2935);
WIRE 16 -1 (-925 2825)(-2150 2825);
FORCEPROP 2 LAST SIG_NAME P5E_CPU0_PE3_TX_C_DN<11>
J 0
(-2035 2835);
DISPLAY 0.638298 (-2035 2835);
WIRE 16 -1 (-925 2975)(-2150 2975);
FORCEPROP 2 LAST SIG_NAME P5E_CPU0_PE2_RX_DP<11>
J 0
(-2035 2985);
DISPLAY 0.638298 (-2035 2985);
WIRE 16 -1 (-925 5425)(-2150 5425);
FORCEPROP 2 LAST SIG_NAME P5E_CPU0_PE2_RX_DP<8>
J 0
(-2035 5435);
DISPLAY 0.638298 (-2035 5435);
WIRE 16 -1 (-925 5525)(-2150 5525);
FORCEPROP 2 LAST SIG_NAME P5E_CPU0_PE3_RX_DP<8>
J 0
(-2035 5535);
DISPLAY 0.638298 (-2035 5535);
WIRE 16 -1 (-925 5575)(-2150 5575);
FORCEPROP 2 LAST SIG_NAME P5E_CPU0_PE3_RX_DN<8>
J 0
(-2035 5585);
DISPLAY 0.638298 (-2035 5585);
WIRE 16 -1 (-925 5375)(-2150 5375);
FORCEPROP 2 LAST SIG_NAME P5E_CPU0_PE2_RX_DN<8>
J 0
(-2035 5385);
DISPLAY 0.638298 (-2035 5385);
WIRE 16 -1 (-925 3675)(-2150 3675);
FORCEPROP 2 LAST SIG_NAME P5E_CPU0_PE3_TX_C_DN<10>
J 0
(-2035 3685);
DISPLAY 0.638298 (-2035 3685);
WIRE 16 -1 (-925 3625)(-2150 3625);
FORCEPROP 2 LAST SIG_NAME P5E_CPU0_PE3_TX_C_DP<10>
J 0
(-2035 3635);
DISPLAY 0.638298 (-2035 3635);
WIRE 16 -1 (-925 3475)(-2150 3475);
FORCEPROP 2 LAST SIG_NAME P5E_CPU0_PE2_TX_C_DN<10>
J 0
(-2035 3485);
DISPLAY 0.638298 (-2035 3485);
WIRE 16 -1 (-925 3525)(-2150 3525);
FORCEPROP 2 LAST SIG_NAME P5E_CPU0_PE2_TX_C_DP<10>
J 0
(-2035 3535);
DISPLAY 0.638298 (-2035 3535);
WIRE 16 -1 (-925 3825)(-2150 3825);
FORCEPROP 2 LAST SIG_NAME P5E_CPU0_PE2_RX_DP<10>
J 0
(-2035 3835);
DISPLAY 0.638298 (-2035 3835);
WIRE 16 -1 (-925 3975)(-2150 3975);
FORCEPROP 2 LAST SIG_NAME P5E_CPU0_PE3_RX_DN<10>
J 0
(-2035 3985);
DISPLAY 0.638298 (-2035 3985);
WIRE 16 -1 (-925 5125)(-2150 5125);
FORCEPROP 2 LAST SIG_NAME P5E_CPU0_PE2_TX_C_DP<8>
J 0
(-2035 5135);
DISPLAY 0.638298 (-2035 5135);
WIRE 16 -1 (-925 5225)(-2150 5225);
FORCEPROP 2 LAST SIG_NAME P5E_CPU0_PE3_TX_C_DP<8>
J 0
(-2035 5235);
DISPLAY 0.638298 (-2035 5235);
WIRE 16 -1 (-925 5275)(-2150 5275);
FORCEPROP 2 LAST SIG_NAME P5E_CPU0_PE3_TX_C_DN<8>
J 0
(-2035 5285);
DISPLAY 0.638298 (-2035 5285);
WIRE 16 -1 (3700 2550)(2450 2550);
FORCEPROP 2 LAST SIG_NAME P5E_CPU0_PE2_TX_C_DP<15>
J 0
(2565 2560);
DISPLAY 0.638298 (2565 2560);
WIRE 16 -1 (3700 2750)(2450 2750);
FORCEPROP 2 LAST SIG_NAME P5E_CPU0_PE3_TX_C_DN<15>
J 0
(2565 2760);
DISPLAY 0.638298 (2565 2760);
WIRE 16 -1 (3700 3450)(2450 3450);
FORCEPROP 2 LAST SIG_NAME P5E_CPU0_PE2_TX_C_DP<14>
J 0
(2565 3460);
DISPLAY 0.638298 (2565 3460);
WIRE 16 -1 (3700 5000)(2450 5000);
FORCEPROP 2 LAST SIG_NAME P5E_CPU0_PE2_TX_C_DN<12>
J 0
(2565 5010);
DISPLAY 0.638298 (2565 5010);
WIRE 16 -1 (3700 5050)(2450 5050);
FORCEPROP 2 LAST SIG_NAME P5E_CPU0_PE2_TX_C_DP<12>
J 0
(2565 5060);
DISPLAY 0.638298 (2565 5060);
WIRE 16 -1 (3700 5150)(2450 5150);
FORCEPROP 2 LAST SIG_NAME P5E_CPU0_PE3_TX_C_DP<12>
J 0
(2565 5160);
DISPLAY 0.638298 (2565 5160);
WIRE 16 -1 (3700 5200)(2450 5200);
FORCEPROP 2 LAST SIG_NAME P5E_CPU0_PE3_TX_C_DN<12>
J 0
(2565 5210);
DISPLAY 0.638298 (2565 5210);
WIRE 16 -1 (3700 5450)(2450 5450);
FORCEPROP 2 LAST SIG_NAME P5E_CPU0_PE3_RX_DN<12>
J 0
(2565 5460);
DISPLAY 0.638298 (2565 5460);
WIRE 16 -1 (3700 5500)(2450 5500);
FORCEPROP 2 LAST SIG_NAME P5E_CPU0_PE3_RX_DP<12>
J 0
(2565 5510);
DISPLAY 0.638298 (2565 5510);
WIRE 16 -1 (3700 5300)(2450 5300);
FORCEPROP 2 LAST SIG_NAME P5E_CPU0_PE2_RX_DN<12>
J 0
(2565 5310);
DISPLAY 0.638298 (2565 5310);
WIRE 16 -1 (3700 5350)(2450 5350);
FORCEPROP 2 LAST SIG_NAME P5E_CPU0_PE2_RX_DP<12>
J 0
(2565 5360);
DISPLAY 0.638298 (2565 5360);
WIRE 16 -1 (-925 2775)(-2150 2775);
FORCEPROP 2 LAST SIG_NAME P5E_CPU0_PE3_TX_C_DP<11>
J 0
(-2035 2785);
DISPLAY 0.638298 (-2035 2785);
WIRE 16 -1 (-925 2625)(-2150 2625);
FORCEPROP 2 LAST SIG_NAME P5E_CPU0_PE2_TX_C_DN<11>
J 0
(-2035 2635);
DISPLAY 0.638298 (-2035 2635);
WIRE 16 -1 (-925 2675)(-2150 2675);
FORCEPROP 2 LAST SIG_NAME P5E_CPU0_PE2_TX_C_DP<11>
J 0
(-2035 2685);
DISPLAY 0.638298 (-2035 2685);
DOT 1 (-1100 4325);
DOT 1 (-1100 2725);
DOT 1 (-1100 2575);
DOT 1 (-1100 3025);
DOT 1 (-1100 2875);
DOT 1 (-1100 3425);
DOT 1 (-1100 3575);
DOT 1 (-1100 3725);
DOT 1 (-1100 4025);
DOT 1 (-1100 3875);
DOT 1 (-1100 4775);
DOT 1 (-1100 5025);
DOT 1 (-1100 5175);
DOT 1 (-1100 5475);
DOT 1 (-1100 5325);
DOT 1 (-1100 3175);
DOT 1 (3475 5400);
DOT 1 (3475 5250);
DOT 1 (3475 5100);
DOT 1 (3475 4950);
DOT 1 (3475 4700);
DOT 1 (3475 4400);
DOT 1 (3475 4550);
DOT 1 (3475 4100);
DOT 1 (3475 4250);
DOT 1 (3475 3950);
DOT 1 (3475 3800);
DOT 1 (3475 3650);
DOT 1 (3475 3500);
DOT 1 (3475 3350);
DOT 1 (3475 3100);
DOT 1 (3475 2950);
DOT 1 (3475 2800);
DOT 1 (3475 2650);
DOT 1 (3475 2500);
DOT 1 (-1100 4175);
DOT 1 (-1100 4475);
DOT 1 (-1100 4625);
FORCENOTE
DP/DN SWAP
(-2950 4225) 0;
DISPLAY LEFT (-2950 4225);
DISPLAY 1.021277 (-2950 4225);
FORCENOTE
DP/DN SWAP
(-2975 4525) 0;
DISPLAY LEFT (-2975 4525);
DISPLAY 1.021277 (-2975 4525);
FORCENOTE
DP/DN SWAP
(1575 4150) 0;
DISPLAY LEFT (1575 4150);
DISPLAY 1.021277 (1575 4150);
FORCENOTE
DP/DN SWAP
(1550 3725) 0;
DISPLAY LEFT (1550 3725);
DISPLAY 1.021277 (1550 3725);
FORCENOTE
DP/DN SWAP
(1550 3850) 0;
DISPLAY LEFT (1550 3850);
DISPLAY 1.021277 (1550 3850);
FORCENOTE
DP/DN SWAP
(-2975 3500) 0;
DISPLAY LEFT (-2975 3500);
DISPLAY 1.021277 (-2975 3500);
FORCENOTE
DP/DN SWAP
(-2975 5100) 0;
DISPLAY LEFT (-2975 5100);
DISPLAY 1.021277 (-2975 5100);
FORCENOTE
DP/DN SWAP
(1550 2850) 0;
DISPLAY LEFT (1550 2850);
DISPLAY 1.021277 (1550 2850);
FORCENOTE
DP/DN SWAP
(1550 3000) 0;
DISPLAY LEFT (1550 3000);
DISPLAY 1.021277 (1550 3000);
FORCENOTE
DP/DN SWAP
(1575 5000) 0;
DISPLAY LEFT (1575 5000);
DISPLAY 1.021277 (1575 5000);
FORCENOTE
DP/DN SWAP
(-3000 2625) 0;
DISPLAY LEFT (-3000 2625);
DISPLAY 1.021277 (-3000 2625);
FORCENOTE
20210527 MODIFY FOR GT
(-3450 6700) 0;
DISPLAY LEFT (-3450 6700);
DISPLAY 2.510638 (-3450 6700);
PAINT PINK (-3450 6700);
FORCENOTE
DP/DN SWAP
(1550 4625) 0;
DISPLAY LEFT (1550 4625);
DISPLAY 1.021277 (1550 4625);
FORCENOTE
DP/DN SWAP
(1550 4450) 0;
DISPLAY LEFT (1550 4450);
DISPLAY 1.021277 (1550 4450);
FORCENOTE
DP/DN SWAP
(1550 5475) 0;
DISPLAY LEFT (1550 5475);
DISPLAY 1.021277 (1550 5475);
FORCENOTE
DP/DN SWAP
(1550 5325) 0;
DISPLAY LEFT (1550 5325);
DISPLAY 1.021277 (1550 5325);
FORCENOTE
DP/DN SWAP
(-3000 3800) 0;
DISPLAY LEFT (-3000 3800);
DISPLAY 1.021277 (-3000 3800);
FORCENOTE
DP/DN SWAP
(-3000 5400) 0;
DISPLAY LEFT (-3000 5400);
DISPLAY 1.021277 (-3000 5400);
FORCENOTE
DP/DN SWAP
(-3000 2950) 0;
DISPLAY LEFT (-3000 2950);
DISPLAY 1.021277 (-3000 2950);
FORCENOTE
DP/DN SWAP
(1550 3400) 0;
DISPLAY LEFT (1550 3400);
DISPLAY 1.021277 (1550 3400);
QUIT
